%FSTAX23Y23*%
%MOIN*%
%SFA1B1*%

%IPPOS*%
%ADD143C,0.120000*%
%ADD150C,0.250000*%
%ADD159C,0.061020*%
%ADD161C,0.075000*%
%ADD162C,0.098430*%
%ADD163O,0.088580X0.177170*%
%ADD164O,0.177170X0.088580*%
%ADD171C,0.016000*%
%ADD172C,0.200000*%
%LNgrandmaster-1*%
%LPD*%
G36*
X07078Y00509D02*
X03114D01*
Y00225*
X02294*
Y00314*
X02262Y00346*
X02234*
X02202Y00314*
Y00225*
X01781*
Y00341*
X01784Y00342*
X01786Y00343*
X01791Y00339*
X01797Y00338*
X01804Y00339*
X01809Y00343*
X01812Y00348*
X01814Y00355*
X01812Y00361*
X01809Y00366*
X01804Y0037*
X01797Y00371*
X01791Y0037*
X01786Y00366*
X01784Y00367*
X01781Y00368*
Y00469*
X01735Y00515*
X01663*
X01618Y0047*
Y00312*
X01321*
Y00512*
X00581*
Y00188*
X00007*
Y04354*
X00019Y04366*
X07078*
Y00509*
G37*
%LNgrandmaster-2*%
%LPC*%
G36*
X0257Y04299D02*
X02564Y04298D01*
X02559Y04294*
X02555Y04289*
X02554Y04283*
X02555Y04276*
X02559Y04271*
X02564Y04267*
X0257Y04266*
X02577Y04267*
X02582Y04271*
X02585Y04276*
X02587Y04283*
X02585Y04289*
X02582Y04294*
X02577Y04298*
X0257Y04299*
G37*
G36*
X01294Y04272D02*
X01288Y04271D01*
X01283Y04267*
X01279Y04262*
X01278Y04256*
X01279Y04249*
X01283Y04244*
X01288Y0424*
X01294Y04239*
X01301Y0424*
X01306Y04244*
X01309Y04249*
X01311Y04256*
X01309Y04262*
X01306Y04267*
X01301Y04271*
X01294Y04272*
G37*
G36*
X02078Y04293D02*
X02007D01*
Y04222*
X02078*
Y04293*
G37*
G36*
X01493Y04289D02*
X01422D01*
Y04218*
X01493*
Y04289*
G37*
G36*
X01557Y04245D02*
X01551Y04244D01*
X01546Y0424*
X01542Y04235*
X01541Y04229*
X01542Y04222*
X01546Y04217*
X01551Y04213*
X01557Y04212*
X01564Y04213*
X01569Y04217*
X01572Y04222*
X01574Y04229*
X01572Y04235*
X01569Y0424*
X01564Y04244*
X01557Y04245*
G37*
G36*
X01345Y04191D02*
X01339Y0419D01*
X01333Y04186*
X0133Y04181*
X01329Y04175*
X0133Y04168*
X01333Y04163*
X01339Y0416*
X01345Y04158*
X01351Y0416*
X01357Y04163*
X0136Y04168*
X01361Y04175*
X0136Y04181*
X01357Y04186*
X01351Y0419*
X01345Y04191*
G37*
G36*
X01569Y04187D02*
X01563Y04186D01*
X01558Y04182*
X01554Y04177*
X01553Y04171*
X01554Y04165*
X01558Y04159*
X01563Y04156*
X01569Y04154*
X01576Y04156*
X01581Y04159*
X01584Y04165*
X01586Y04171*
X01584Y04177*
X01581Y04182*
X01576Y04186*
X01569Y04187*
G37*
G36*
X01779Y04172D02*
X01773Y04171D01*
X01768Y04167*
X01764Y04162*
X01763Y04156*
X01764Y04149*
X01768Y04144*
X01773Y0414*
X01779Y04139*
X01786Y0414*
X01791Y04144*
X01794Y04149*
X01796Y04156*
X01794Y04162*
X01791Y04167*
X01786Y04171*
X01779Y04172*
G37*
G36*
X02043Y04193D02*
X02034Y04192D01*
X02025Y04188*
X02017Y04183*
X02012Y04175*
X02008Y04167*
X02007Y04157*
X02008Y04148*
X02012Y04139*
X02017Y04132*
X02025Y04126*
X02034Y04123*
X02043Y04122*
X02052Y04123*
X02061Y04126*
X02068Y04132*
X02074Y04139*
X02077Y04148*
X02079Y04157*
X02077Y04167*
X02074Y04175*
X02068Y04183*
X02061Y04188*
X02052Y04192*
X02043Y04193*
G37*
G36*
X01457Y04189D02*
X01448Y04188D01*
X01439Y04184*
X01432Y04179*
X01426Y04171*
X01423Y04163*
X01421Y04153*
X01423Y04144*
X01426Y04136*
X01432Y04128*
X01439Y04122*
X01448Y04119*
X01457Y04118*
X01466Y04119*
X01475Y04122*
X01483Y04128*
X01488Y04136*
X01492Y04144*
X01493Y04153*
X01492Y04163*
X01488Y04171*
X01483Y04179*
X01475Y04184*
X01466Y04188*
X01457Y04189*
G37*
G36*
X03958Y04152D02*
X03951Y04151D01*
X03945Y04148*
X03939Y04144*
X03935Y04139*
X03933Y04132*
X03932Y04126*
X03933Y04119*
X03935Y04113*
X03939Y04107*
X03945Y04103*
X03951Y04101*
X03958Y041*
X03964Y04101*
X03971Y04103*
X03976Y04107*
X0398Y04113*
X03983Y04119*
X03984Y04126*
X03983Y04132*
X0398Y04139*
X03976Y04144*
X03971Y04148*
X03964Y04151*
X03958Y04152*
G37*
G36*
X03784D02*
X03778Y04151D01*
X03771Y04148*
X03766Y04144*
X03762Y04139*
X03759Y04132*
X03758Y04126*
X03759Y04119*
X03762Y04113*
X03766Y04107*
X03771Y04103*
X03778Y04101*
X03784Y041*
X03791Y04101*
X03797Y04103*
X03803Y04107*
X03807Y04113*
X03809Y04119*
X0381Y04126*
X03809Y04132*
X03807Y04139*
X03803Y04144*
X03797Y04148*
X03791Y04151*
X03784Y04152*
G37*
G36*
X04754Y04132D02*
X04748Y04131D01*
X04743Y04127*
X04739Y04122*
X04738Y04115*
X04739Y04109*
X04743Y04104*
X04748Y041*
X04754Y04099*
X0476Y041*
X04766Y04104*
X04769Y04109*
X04771Y04115*
X04769Y04122*
X04766Y04127*
X0476Y04131*
X04754Y04132*
G37*
G36*
X02146Y0412D02*
X02139Y04118D01*
X02134Y04115*
X02131Y0411*
X02129Y04103*
X02131Y04097*
X02134Y04092*
X02139Y04088*
X02146Y04087*
X02152Y04088*
X02157Y04092*
X02161Y04097*
X02162Y04103*
X02161Y0411*
X02157Y04115*
X02152Y04118*
X02146Y0412*
G37*
G36*
X00285Y04223D02*
X00271Y04221D01*
X00258Y04217*
X00246Y04211*
X00235Y04202*
X00226Y04191*
X00219Y04179*
X00215Y04165*
X00214Y04152*
X00215Y04138*
X00219Y04124*
X00226Y04112*
X00235Y04101*
X00246Y04093*
X00258Y04086*
X00271Y04082*
X00285Y04081*
X00299Y04082*
X00312Y04086*
X00324Y04093*
X00335Y04101*
X00344Y04112*
X0035Y04124*
X00355Y04138*
X00356Y04152*
X00355Y04165*
X0035Y04179*
X00344Y04191*
X00335Y04202*
X00324Y04211*
X00312Y04217*
X00299Y04221*
X00285Y04223*
G37*
G36*
X05267Y04105D02*
X0526Y04103D01*
X05255Y041*
X05251Y04095*
X0525Y04088*
X05251Y04082*
X05255Y04077*
X0526Y04073*
X05267Y04072*
X05273Y04073*
X05278Y04077*
X05282Y04082*
X05283Y04088*
X05282Y04095*
X05278Y041*
X05273Y04103*
X05267Y04105*
G37*
G36*
X02253Y04102D02*
X02247Y04101D01*
X02242Y04098*
X02238Y04092*
X02237Y04086*
X02238Y0408*
X02242Y04075*
X02247Y04071*
X02253Y0407*
X0226Y04071*
X02265Y04075*
X02269Y0408*
X0227Y04086*
X02269Y04092*
X02265Y04098*
X0226Y04101*
X02253Y04102*
G37*
G36*
X03504Y04102D02*
X03498Y04101D01*
X03493Y04097*
X03489Y04092*
X03488Y04086*
X03489Y04079*
X03493Y04074*
X03498Y0407*
X03504Y04069*
X03511Y0407*
X03516Y04074*
X03519Y04079*
X03521Y04086*
X03519Y04092*
X03516Y04097*
X03511Y04101*
X03504Y04102*
G37*
G36*
X03294Y04127D02*
X03284Y04126D01*
X03274Y04121*
X03265Y04115*
X03259Y04106*
X03254Y04096*
X03253Y04086*
X03254Y04075*
X03259Y04065*
X03265Y04056*
X03274Y0405*
X03284Y04046*
X03294Y04044*
X03305Y04046*
X03315Y0405*
X03324Y04056*
X0333Y04065*
X03334Y04075*
X03336Y04086*
X03334Y04096*
X0333Y04106*
X03324Y04115*
X03315Y04121*
X03305Y04126*
X03294Y04127*
G37*
G36*
X02994D02*
X02984Y04126D01*
X02974Y04121*
X02965Y04115*
X02959Y04106*
X02954Y04096*
X02953Y04086*
X02954Y04075*
X02959Y04065*
X02965Y04056*
X02974Y0405*
X02984Y04046*
X02994Y04044*
X03005Y04046*
X03015Y0405*
X03024Y04056*
X0303Y04065*
X03034Y04075*
X03036Y04086*
X03034Y04096*
X0303Y04106*
X03024Y04115*
X03015Y04121*
X03005Y04126*
X02994Y04127*
G37*
G36*
X069Y0416D02*
X06887Y04159D01*
X06874Y04155*
X06862Y04149*
X06852Y04141*
X06844Y0413*
X06837Y04119*
X06834Y04106*
X06832Y04093*
X06834Y0408*
X06837Y04067*
X06844Y04056*
X06852Y04045*
X06862Y04037*
X06874Y04031*
X06887Y04027*
X069Y04026*
X06913Y04027*
X06925Y04031*
X06937Y04037*
X06947Y04045*
X06956Y04056*
X06962Y04067*
X06966Y0408*
X06967Y04093*
X06966Y04106*
X06962Y04119*
X06956Y0413*
X06947Y04141*
X06937Y04149*
X06925Y04155*
X06913Y04159*
X069Y0416*
G37*
G36*
X06569D02*
X06556Y04159D01*
X06543Y04155*
X06532Y04149*
X06521Y04141*
X06513Y0413*
X06507Y04119*
X06503Y04106*
X06502Y04093*
X06503Y0408*
X06507Y04067*
X06513Y04056*
X06521Y04045*
X06532Y04037*
X06543Y04031*
X06556Y04027*
X06569Y04026*
X06582Y04027*
X06595Y04031*
X06606Y04037*
X06617Y04045*
X06625Y04056*
X06631Y04067*
X06635Y0408*
X06636Y04093*
X06635Y04106*
X06631Y04119*
X06625Y0413*
X06617Y04141*
X06606Y04149*
X06595Y04155*
X06582Y04159*
X06569Y0416*
G37*
G36*
X02043Y04093D02*
X02034Y04092D01*
X02025Y04088*
X02017Y04083*
X02012Y04075*
X02008Y04067*
X02007Y04057*
X02008Y04048*
X02012Y04039*
X02017Y04032*
X02025Y04026*
X02034Y04023*
X02043Y04022*
X02052Y04023*
X02061Y04026*
X02068Y04032*
X02074Y04039*
X02077Y04048*
X02079Y04057*
X02077Y04067*
X02074Y04075*
X02068Y04083*
X02061Y04088*
X02052Y04092*
X02043Y04093*
G37*
G36*
X01457Y04089D02*
X01448Y04088D01*
X01439Y04084*
X01432Y04079*
X01426Y04071*
X01423Y04063*
X01421Y04053*
X01423Y04044*
X01426Y04036*
X01432Y04028*
X01439Y04022*
X01448Y04019*
X01457Y04018*
X01466Y04019*
X01475Y04022*
X01483Y04028*
X01488Y04036*
X01492Y04044*
X01493Y04053*
X01492Y04063*
X01488Y04071*
X01483Y04079*
X01475Y04084*
X01466Y04088*
X01457Y04089*
G37*
G36*
X01903Y04034D02*
X01897Y04033D01*
X01892Y04029*
X01888Y04024*
X01887Y04018*
X01888Y04011*
X01892Y04006*
X01897Y04002*
X01903Y04001*
X0191Y04002*
X01915Y04006*
X01918Y04011*
X0192Y04018*
X01918Y04024*
X01915Y04029*
X0191Y04033*
X01903Y04034*
G37*
G36*
X02353Y04034D02*
X02347Y04032D01*
X02341Y04029*
X02338Y04023*
X02337Y04017*
X02338Y04011*
X02341Y04006*
X02347Y04002*
X02353Y04001*
X02359Y04002*
X02364Y04006*
X02368Y04011*
X02369Y04017*
X02368Y04023*
X02364Y04029*
X02359Y04032*
X02353Y04034*
G37*
G36*
X05723Y04083D02*
X05708Y04081D01*
X05694Y04075*
X05682Y04066*
X05673Y04054*
X05667Y0404*
X05665Y04025*
X05667Y0401*
X05673Y03996*
X05682Y03984*
X05694Y03975*
X05708Y03969*
X05723Y03967*
X05738Y03969*
X05752Y03975*
X05764Y03984*
X05773Y03996*
X05779Y0401*
X05781Y04025*
X05779Y0404*
X05773Y04054*
X05764Y04066*
X05752Y04075*
X05738Y04081*
X05723Y04083*
G37*
G36*
X01408Y03996D02*
X01402Y03995D01*
X01396Y03991*
X01393Y03986*
X01392Y0398*
X01393Y03974*
X01396Y03968*
X01402Y03965*
X01408Y03964*
X01414Y03965*
X0142Y03968*
X01423Y03974*
X01424Y0398*
X01423Y03986*
X0142Y03991*
X01414Y03995*
X01408Y03996*
G37*
G36*
X02084Y03912D02*
X02078Y03911D01*
X02073Y03907*
X02069Y03902*
X02068Y03896*
X02069Y03889*
X02069Y03889*
X02066Y03885*
X02066Y03886*
X02059Y03887*
X02053Y03886*
X02048Y03882*
X02044Y03877*
X02043Y03871*
X02044Y03864*
X02048Y03859*
X02053Y03855*
X02059Y03854*
X02066Y03855*
X02071Y03859*
X02074Y03864*
X02076Y03871*
X02074Y03877*
X02074Y03877*
X02078Y03881*
X02078Y0388*
X02084Y03879*
X02091Y0388*
X02096Y03884*
X02099Y03889*
X02101Y03896*
X02099Y03902*
X02096Y03907*
X02091Y03911*
X02084Y03912*
G37*
G36*
X02029Y03852D02*
X02023Y03851D01*
X02018Y03847*
X02014Y03842*
X02013Y03836*
X02013Y03835*
X02013Y03834*
X02009Y03831*
X02004Y03832*
X01998Y03831*
X01993Y03827*
X01989Y03822*
X01988Y03816*
X01989Y03809*
X01993Y03804*
X01998Y038*
X02004Y03799*
X02011Y038*
X02016Y03804*
X02019Y03809*
X02021Y03816*
X02021Y03816*
X02021Y03817*
X02025Y0382*
X02029Y03819*
X02036Y0382*
X02041Y03824*
X02044Y03829*
X02046Y03836*
X02044Y03842*
X02041Y03847*
X02036Y03851*
X02029Y03852*
G37*
G36*
X03699D02*
X03693Y03851D01*
X03688Y03847*
X03684Y03842*
X03683Y03836*
X03684Y03829*
X03688Y03824*
X03693Y0382*
X03699Y03819*
X03706Y0382*
X03711Y03824*
X03714Y03829*
X03716Y03836*
X03714Y03842*
X03711Y03847*
X03706Y03851*
X03699Y03852*
G37*
G36*
X03014Y03847D02*
X03008Y03846D01*
X03003Y03842*
X02999Y03837*
X02998Y03831*
X02999Y03824*
X03003Y03819*
X03008Y03815*
X03014Y03814*
X03021Y03815*
X03026Y03819*
X03029Y03824*
X03031Y03831*
X03029Y03837*
X03026Y03842*
X03021Y03846*
X03014Y03847*
G37*
G36*
X03829Y03822D02*
X03823Y03821D01*
X03818Y03817*
X03814Y03812*
X03813Y03806*
X03814Y03799*
X03818Y03794*
X03823Y0379*
X03829Y03789*
X03836Y0379*
X03841Y03794*
X03844Y03799*
X03846Y03806*
X03844Y03812*
X03841Y03817*
X03836Y03821*
X03829Y03822*
G37*
G36*
X03539D02*
X03533Y03821D01*
X03528Y03817*
X03524Y03812*
X03523Y03806*
X03524Y03799*
X03528Y03794*
X03533Y0379*
X03539Y03789*
X03546Y0379*
X03551Y03794*
X03554Y03799*
X03556Y03806*
X03554Y03812*
X03551Y03817*
X03546Y03821*
X03539Y03822*
G37*
G36*
X03219D02*
X03213Y03821D01*
X03208Y03817*
X03204Y03812*
X03203Y03806*
X03204Y03799*
X03208Y03794*
X03213Y0379*
X03219Y03789*
X03226Y0379*
X03231Y03794*
X03234Y03799*
X03236Y03806*
X03234Y03812*
X03231Y03817*
X03226Y03821*
X03219Y03822*
G37*
G36*
X05723Y03902D02*
X05708Y039D01*
X05694Y03894*
X05682Y03885*
X05673Y03873*
X05667Y03859*
X05665Y03844*
X05667Y03829*
X05673Y03815*
X05682Y03803*
X05694Y03794*
X05708Y03788*
X05723Y03786*
X05738Y03788*
X05752Y03794*
X05764Y03803*
X05773Y03815*
X05779Y03829*
X05781Y03844*
X05779Y03859*
X05773Y03873*
X05764Y03885*
X05752Y03894*
X05738Y039*
X05723Y03902*
G37*
G36*
X02722Y03802D02*
X02716Y03801D01*
X0271Y03797*
X02707Y03792*
X02706Y03786*
X02707Y03779*
X0271Y03774*
X02716Y03771*
X02722Y03769*
X02728Y03771*
X02733Y03774*
X02737Y03779*
X02738Y03786*
X02737Y03792*
X02733Y03797*
X02728Y03801*
X02722Y03802*
G37*
G36*
X06169Y03877D02*
X0607D01*
X06055Y03875*
X06041Y03869*
X06029Y0386*
X0602Y03848*
X06014Y03834*
X06012Y03819*
X06014Y03804*
X0602Y0379*
X06029Y03779*
X06041Y03769*
X06055Y03764*
X0607Y03762*
X06169*
X06183Y03764*
X06197Y03769*
X06209Y03779*
X06219Y0379*
X06224Y03804*
X06226Y03819*
X06224Y03834*
X06219Y03848*
X06209Y0386*
X06197Y03869*
X06183Y03875*
X06169Y03877*
G37*
G36*
X04254Y03792D02*
X04248Y03791D01*
X04243Y03787*
X04239Y03782*
X04238Y03776*
X04239Y03769*
X04243Y03764*
X04248Y0376*
X04254Y03759*
X04261Y0376*
X04266Y03764*
X04269Y03769*
X04271Y03776*
X04269Y03782*
X04266Y03787*
X04261Y03791*
X04254Y03792*
G37*
G36*
X069Y03863D02*
X06885Y03861D01*
X06871Y03856*
X06859Y03846*
X0685Y03834*
X06844Y03821*
X06842Y03806*
X06844Y03791*
X0685Y03777*
X06859Y03765*
X06871Y03756*
X06885Y0375*
X069Y03748*
X06915Y0375*
X06929Y03756*
X06941Y03765*
X0695Y03777*
X06955Y03791*
X06957Y03806*
X06955Y03821*
X0695Y03834*
X06941Y03846*
X06929Y03856*
X06915Y03861*
X069Y03863*
G37*
G36*
X06734D02*
X06719Y03861D01*
X06705Y03856*
X06694Y03846*
X06684Y03834*
X06679Y03821*
X06677Y03806*
X06679Y03791*
X06684Y03777*
X06694Y03765*
X06705Y03756*
X06719Y0375*
X06734Y03748*
X06749Y0375*
X06763Y03756*
X06775Y03765*
X06784Y03777*
X0679Y03791*
X06792Y03806*
X0679Y03821*
X06784Y03834*
X06775Y03846*
X06763Y03856*
X06749Y03861*
X06734Y03863*
G37*
G36*
X06569D02*
X06554Y03861D01*
X0654Y03856*
X06528Y03846*
X06519Y03834*
X06513Y03821*
X06511Y03806*
X06513Y03791*
X06519Y03777*
X06528Y03765*
X0654Y03756*
X06554Y0375*
X06569Y03748*
X06584Y0375*
X06598Y03756*
X0661Y03765*
X06619Y03777*
X06625Y03791*
X06627Y03806*
X06625Y03821*
X06619Y03834*
X0661Y03846*
X06598Y03856*
X06584Y03861*
X06569Y03863*
G37*
G36*
X03699Y03767D02*
X03693Y03766D01*
X03688Y03762*
X03684Y03757*
X03683Y03751*
X03684Y03744*
X03688Y03739*
X03693Y03735*
X03699Y03734*
X03706Y03735*
X03711Y03739*
X03714Y03744*
X03716Y03751*
X03714Y03757*
X03711Y03762*
X03706Y03766*
X03699Y03767*
G37*
G36*
X02993D02*
X02987Y03766D01*
X02981Y03762*
X02978Y03757*
X02977Y03751*
X02978Y03744*
X02981Y03739*
X02987Y03735*
X02993Y03734*
X02999Y03735*
X03004Y03739*
X03008Y03744*
X03009Y03751*
X03008Y03757*
X03004Y03762*
X02999Y03766*
X02993Y03767*
G37*
G36*
X06294Y03717D02*
X06288Y03716D01*
X06283Y03712*
X06279Y03707*
X06278Y03701*
X06279Y03694*
X06283Y03689*
X06288Y03685*
X06294Y03684*
X06301Y03685*
X06306Y03689*
X06309Y03694*
X06311Y03701*
X06309Y03707*
X06306Y03712*
X06301Y03716*
X06294Y03717*
G37*
G36*
X01849D02*
X01843Y03716D01*
X01838Y03712*
X01834Y03707*
X01833Y03701*
X01834Y03694*
X01838Y03689*
X01843Y03685*
X01849Y03684*
X01856Y03685*
X01861Y03689*
X01864Y03694*
X01866Y03701*
X01864Y03707*
X01861Y03712*
X01856Y03716*
X01849Y03717*
G37*
G36*
X04049Y03681D02*
X04043Y0368D01*
X04038Y03676*
X04034Y03671*
X04033Y03665*
X04034Y03658*
X04038Y03653*
X04043Y03649*
X04049Y03648*
X04056Y03649*
X04061Y03653*
X04064Y03658*
X04066Y03665*
X04064Y03671*
X04061Y03676*
X04056Y0368*
X04049Y03681*
G37*
G36*
X02679Y03677D02*
X02673Y03676D01*
X02668Y03672*
X02664Y03667*
X02663Y03661*
X02664Y03654*
X02668Y03649*
X02673Y03645*
X02679Y03644*
X02686Y03645*
X02691Y03649*
X02694Y03654*
X02696Y03661*
X02694Y03667*
X02691Y03672*
X02686Y03676*
X02679Y03677*
G37*
G36*
X01754D02*
X01748Y03676D01*
X01743Y03672*
X01739Y03667*
X01738Y03661*
X01739Y03654*
X01743Y03649*
X01748Y03645*
X01754Y03644*
X01761Y03645*
X01766Y03649*
X01769Y03654*
X01771Y03661*
X01769Y03667*
X01766Y03672*
X01761Y03676*
X01754Y03677*
G37*
G36*
X03424Y03652D02*
X03418Y03651D01*
X03413Y03647*
X03409Y03642*
X03408Y03636*
X03409Y03629*
X03413Y03624*
X03418Y0362*
X03424Y03619*
X03431Y0362*
X03436Y03624*
X03439Y03629*
X03441Y03636*
X03439Y03642*
X03436Y03647*
X03431Y03651*
X03424Y03652*
G37*
G36*
X02799Y03632D02*
X02793Y03631D01*
X02788Y03627*
X02784Y03622*
X02783Y03616*
X02784Y03609*
X02788Y03604*
X02793Y036*
X02799Y03599*
X02806Y036*
X02811Y03604*
X02814Y03609*
X02816Y03616*
X02814Y03622*
X02811Y03627*
X02806Y03631*
X02799Y03632*
G37*
G36*
X02139Y03627D02*
X02133Y03626D01*
X02128Y03622*
X02124Y03617*
X02123Y03611*
X02124Y03604*
X02128Y03599*
X02133Y03595*
X02139Y03594*
X02146Y03595*
X02151Y03599*
X02154Y03604*
X02156Y03611*
X02154Y03617*
X02151Y03622*
X02146Y03626*
X02139Y03627*
G37*
G36*
X01884Y03617D02*
X01878Y03616D01*
X01873Y03612*
X01869Y03607*
X01868Y03601*
X01869Y03594*
X01873Y03589*
X01878Y03585*
X01884Y03584*
X01891Y03585*
X01896Y03589*
X01899Y03594*
X01901Y03601*
X01899Y03607*
X01896Y03612*
X01891Y03616*
X01884Y03617*
G37*
G36*
X03239Y03612D02*
X03233Y03611D01*
X03228Y03607*
X03224Y03602*
X03223Y03596*
X03224Y03589*
X03228Y03584*
X03233Y0358*
X03239Y03579*
X03246Y0358*
X03251Y03584*
X03254Y03589*
X03256Y03596*
X03254Y03602*
X03251Y03607*
X03246Y03611*
X03239Y03612*
G37*
G36*
X01549Y03637D02*
X01543Y03636D01*
X01538Y03632*
X01534Y03627*
X01533Y03621*
X01534Y03614*
X01538Y03609*
X01543Y03605*
X01549Y03604*
X01556Y03605*
X01556Y03606*
X01559Y03602*
X01559Y03602*
X01558Y03596*
X01559Y03589*
X01563Y03584*
X01568Y0358*
X01574Y03579*
X01581Y0358*
X01586Y03584*
X01589Y03589*
X01591Y03596*
X01589Y03602*
X01586Y03607*
X01581Y03611*
X01574Y03612*
X01568Y03611*
X01568Y0361*
X01564Y03614*
X01564Y03614*
X01566Y03621*
X01564Y03627*
X01561Y03632*
X01556Y03636*
X01549Y03637*
G37*
G36*
X02422Y03624D02*
X02413Y03623D01*
X02405Y03617*
X024Y0361*
X02398Y03601*
X024Y03592*
X02405Y03584*
X02413Y03579*
X02422Y03577*
X02431Y03579*
X02438Y03584*
X02443Y03592*
X02445Y03601*
X02443Y0361*
X02438Y03617*
X02431Y03623*
X02422Y03624*
G37*
G36*
X02774Y03582D02*
X02768Y03581D01*
X02763Y03577*
X02759Y03572*
X02758Y03566*
X02759Y03559*
X02763Y03554*
X02768Y0355*
X02774Y03549*
X02781Y0355*
X02786Y03554*
X02789Y03559*
X02791Y03566*
X02789Y03572*
X02786Y03577*
X02781Y03581*
X02774Y03582*
G37*
G36*
X0144Y03573D02*
X01434Y03572D01*
X01429Y03568*
X01425Y03563*
X01424Y03557*
X01425Y0355*
X01429Y03545*
X01434Y03541*
X0144Y0354*
X01447Y03541*
X01452Y03545*
X01455Y0355*
X01457Y03557*
X01455Y03563*
X01452Y03568*
X01447Y03572*
X0144Y03573*
G37*
G36*
X05994Y03568D02*
X05988Y03567D01*
X05983Y03563*
X05979Y03558*
X05978Y03552*
X05979Y03545*
X05983Y0354*
X05988Y03536*
X05994Y03535*
X06001Y03536*
X06006Y0354*
X06009Y03545*
X06011Y03552*
X06009Y03558*
X06006Y03563*
X06001Y03567*
X05994Y03568*
G37*
G36*
X02434Y03562D02*
X02428Y03561D01*
X02423Y03557*
X02419Y03552*
X02418Y03546*
X02419Y03539*
X02423Y03534*
X02428Y0353*
X02434Y03529*
X02441Y0353*
X02446Y03534*
X02449Y03539*
X02451Y03546*
X02449Y03552*
X02446Y03557*
X02441Y03561*
X02434Y03562*
G37*
G36*
X02254Y03552D02*
X02248Y03551D01*
X02243Y03547*
X02239Y03542*
X02238Y03536*
X02239Y03529*
X02242Y03525*
X02239Y03521*
X02234Y03522*
X02228Y03521*
X02223Y03517*
X02219Y03512*
X02218Y03506*
X02219Y03499*
X02223Y03494*
X02228Y0349*
X02234Y03489*
X02241Y0349*
X02246Y03494*
X02249Y03499*
X02251Y03506*
X02249Y03512*
X02247Y03516*
X0225Y0352*
X02254Y03519*
X02261Y0352*
X02266Y03524*
X02269Y03529*
X02271Y03536*
X02269Y03542*
X02266Y03547*
X02261Y03551*
X02254Y03552*
G37*
G36*
X05274Y03527D02*
X05268Y03526D01*
X05263Y03522*
X05259Y03517*
X05258Y03511*
X05259Y03504*
X05263Y03499*
X05268Y03495*
X05274Y03494*
X05281Y03495*
X05286Y03499*
X05289Y03504*
X05291Y03511*
X05289Y03517*
X05286Y03522*
X05281Y03526*
X05274Y03527*
G37*
G36*
X03622Y03502D02*
X03616Y03501D01*
X03611Y03497*
X03607Y03492*
X03606Y03486*
X03607Y03479*
X03611Y03474*
X03616Y0347*
X03622Y03469*
X03629Y0347*
X03634Y03474*
X03637Y03479*
X03639Y03486*
X03637Y03492*
X03634Y03497*
X03629Y03501*
X03622Y03502*
G37*
G36*
X02579D02*
X02573Y03501D01*
X02568Y03497*
X02564Y03492*
X02563Y03486*
X02564Y03479*
X02568Y03474*
X02573Y0347*
X02579Y03469*
X02586Y0347*
X02591Y03474*
X02594Y03479*
X02596Y03486*
X02594Y03492*
X02591Y03497*
X02586Y03501*
X02579Y03502*
G37*
G36*
X03529Y03497D02*
X03523Y03496D01*
X03518Y03492*
X03514Y03487*
X03513Y03481*
X03514Y03474*
X03518Y03469*
X03523Y03465*
X03529Y03464*
X03536Y03465*
X03541Y03469*
X03544Y03474*
X03546Y03481*
X03544Y03487*
X03541Y03492*
X03536Y03496*
X03529Y03497*
G37*
G36*
X02389D02*
X02383Y03496D01*
X02378Y03492*
X02374Y03487*
X02373Y03481*
X02374Y03474*
X02378Y03469*
X02383Y03465*
X02389Y03464*
X02396Y03465*
X02401Y03469*
X02404Y03474*
X02406Y03481*
X02404Y03487*
X02401Y03492*
X02396Y03496*
X02389Y03497*
G37*
G36*
X06509Y03472D02*
X06503Y03471D01*
X06498Y03467*
X06494Y03462*
X06493Y03456*
X06494Y03449*
X06498Y03444*
X06503Y0344*
X06509Y03439*
X06516Y0344*
X06521Y03444*
X06524Y03449*
X06526Y03456*
X06524Y03462*
X06521Y03467*
X06516Y03471*
X06509Y03472*
G37*
G36*
X03436Y03473D02*
X0343Y03472D01*
X03425Y03468*
X03421Y03463*
X0342Y03457*
X03421Y0345*
X03425Y03445*
X0343Y03441*
X03436Y0344*
X03443Y03441*
X03448Y03445*
X0345Y03448*
X0345Y03448*
X03456Y03447*
X03458Y03444*
X03463Y0344*
X03469Y03439*
X03476Y0344*
X03481Y03444*
X03484Y03449*
X03486Y03456*
X03484Y03462*
X03481Y03467*
X03476Y03471*
X03469Y03472*
X03463Y03471*
X03458Y03467*
X03456Y03464*
X03456Y03464*
X0345Y03465*
X03448Y03468*
X03443Y03472*
X03436Y03473*
G37*
G36*
X03358Y03464D02*
X03352Y03463D01*
X03347Y03459*
X03343Y03454*
X03342Y03448*
X03343Y03441*
X03347Y03436*
X03352Y03432*
X03358Y03431*
X03365Y03432*
X0337Y03436*
X03373Y03441*
X03374Y03443*
X03379*
X03379Y0344*
X03383Y03435*
X03388Y03431*
X03394Y0343*
X03401Y03431*
X03406Y03435*
X03409Y0344*
X03411Y03447*
X03409Y03453*
X03406Y03458*
X03401Y03462*
X03394Y03463*
X03388Y03462*
X03383Y03458*
X03379Y03453*
X03379Y03451*
X03374*
X03373Y03454*
X0337Y03459*
X03365Y03463*
X03358Y03464*
G37*
G36*
X02422Y03467D02*
X02413Y03465D01*
X02405Y0346*
X024Y03452*
X02398Y03443*
X024Y03434*
X02405Y03427*
X02413Y03422*
X02422Y0342*
X02431Y03422*
X02438Y03427*
X02443Y03434*
X02445Y03443*
X02443Y03452*
X02438Y0346*
X02431Y03465*
X02422Y03467*
G37*
G36*
X06479Y03442D02*
X06473Y03441D01*
X06468Y03437*
X06464Y03432*
X06463Y03426*
X06464Y03419*
X06468Y03414*
X06473Y0341*
X06479Y03409*
X06486Y0341*
X06491Y03414*
X06494Y03419*
X06496Y03426*
X06494Y03432*
X06491Y03437*
X06486Y03441*
X06479Y03442*
G37*
G36*
X02634Y03422D02*
X02628Y03421D01*
X02623Y03417*
X02619Y03412*
X02618Y03406*
X02619Y03399*
X02623Y03394*
X02628Y0339*
X02634Y03389*
X02641Y0339*
X02646Y03394*
X02649Y03399*
X02651Y03406*
X02649Y03412*
X02646Y03417*
X02641Y03421*
X02634Y03422*
G37*
G36*
X06447Y03412D02*
X06441Y03411D01*
X06436Y03407*
X06432Y03402*
X06431Y03396*
X06432Y03389*
X06436Y03384*
X06441Y0338*
X06447Y03379*
X06453Y0338*
X06459Y03384*
X06462Y03389*
X06463Y03396*
X06462Y03402*
X06459Y03407*
X06453Y03411*
X06447Y03412*
G37*
G36*
X03068Y03411D02*
X03062Y0341D01*
X03057Y03407*
X03053Y03401*
X03052Y03395*
X03053Y03389*
X03057Y03384*
X03062Y0338*
X03068Y03379*
X03075Y0338*
X0308Y03384*
X03083Y03389*
X03085Y03395*
X03083Y03401*
X0308Y03407*
X03075Y0341*
X03068Y03411*
G37*
G36*
X06409Y03387D02*
X06403Y03386D01*
X06398Y03382*
X06394Y03377*
X06393Y03371*
X06394Y03364*
X06398Y03359*
X06403Y03355*
X06409Y03354*
X06416Y03355*
X06421Y03359*
X06424Y03364*
X06426Y03371*
X06424Y03377*
X06421Y03382*
X06416Y03386*
X06409Y03387*
G37*
G36*
X03302Y0336D02*
X03296Y03359D01*
X03291Y03355*
X03287Y0335*
X03286Y03344*
X03287Y03337*
X03291Y03332*
X03296Y03328*
X03302Y03327*
X03309Y03328*
X03314Y03332*
X03317Y03337*
X03319Y03344*
X03317Y0335*
X03314Y03355*
X03309Y03359*
X03302Y0336*
G37*
G36*
X06354Y03347D02*
X06348Y03346D01*
X06343Y03342*
X06339Y03337*
X06338Y03331*
X06339Y03324*
X06343Y03319*
X06348Y03316*
X06354Y03314*
X0636Y03316*
X06366Y03319*
X06369Y03324*
X06371Y03331*
X06369Y03337*
X06366Y03342*
X0636Y03346*
X06354Y03347*
G37*
G36*
X03542Y03335D02*
X03536Y03334D01*
X03531Y0333*
X03527Y03325*
X03526Y03319*
X03527Y03312*
X03531Y03307*
X03536Y03303*
X03542Y03302*
X03549Y03303*
X03554Y03307*
X03557Y03312*
X03559Y03319*
X03557Y03325*
X03554Y0333*
X03549Y03334*
X03542Y03335*
G37*
G36*
X03263Y0332D02*
X03257Y03318D01*
X03252Y03315*
X03248Y0331*
X03247Y03303*
X03248Y03297*
X03252Y03292*
X03257Y03288*
X03263Y03287*
X03269Y03288*
X03275Y03292*
X03278Y03297*
X0328Y03303*
X03278Y0331*
X03275Y03315*
X03269Y03318*
X03263Y0332*
G37*
G36*
X03491Y03313D02*
X03485Y03312D01*
X0348Y03308*
X03476Y03303*
X03475Y03297*
X03476Y0329*
X0348Y03285*
X03485Y03281*
X03491Y0328*
X03498Y03281*
X03503Y03285*
X03506Y0329*
X03508Y03297*
X03506Y03303*
X03503Y03308*
X03498Y03312*
X03491Y03313*
G37*
G36*
X03653Y03309D02*
X03647Y03308D01*
X03642Y03304*
X03638Y03299*
X03637Y03293*
X03638Y03286*
X03642Y03281*
X03647Y03277*
X03653Y03276*
X0366Y03277*
X03665Y03281*
X03668Y03286*
X0367Y03293*
X03668Y03299*
X03665Y03304*
X0366Y03308*
X03653Y03309*
G37*
G36*
X06444Y03307D02*
X06438Y03306D01*
X06433Y03302*
X06429Y03297*
X06428Y03291*
X06429Y03284*
X06433Y03279*
X06438Y03275*
X06444Y03274*
X06451Y03275*
X06456Y03279*
X06459Y03284*
X06461Y03291*
X06459Y03297*
X06456Y03302*
X06451Y03306*
X06444Y03307*
G37*
G36*
X0259Y03304D02*
X02584Y03303D01*
X02579Y03299*
X02575Y03294*
X02574Y03288*
X02575Y03281*
X02579Y03276*
X02584Y03272*
X0259Y03271*
X02597Y03272*
X02602Y03276*
X02605Y03281*
X02607Y03288*
X02605Y03294*
X02602Y03299*
X02597Y03303*
X0259Y03304*
G37*
G36*
X03374Y03289D02*
X03368Y03288D01*
X03363Y03284*
X03359Y03279*
X03358Y03273*
X03359Y03266*
X03363Y03261*
X03368Y03257*
X03374Y03256*
X03381Y03257*
X03386Y03261*
X03389Y03266*
X03391Y03273*
X03389Y03279*
X03386Y03284*
X03381Y03288*
X03374Y03289*
G37*
G36*
X06334Y03282D02*
X06328Y03281D01*
X06323Y03277*
X06319Y03272*
X06318Y03266*
X06319Y03259*
X06323Y03254*
X06328Y0325*
X06334Y03249*
X06341Y0325*
X06346Y03254*
X06349Y03259*
X06351Y03266*
X06349Y03272*
X06346Y03277*
X06341Y03281*
X06334Y03282*
G37*
G36*
X03744Y03277D02*
X03738Y03276D01*
X03733Y03272*
X03729Y03267*
X03728Y03261*
X03729Y03254*
X03733Y03249*
X03738Y03245*
X03744Y03244*
X03751Y03245*
X03756Y03249*
X03759Y03254*
X03761Y03261*
X03759Y03267*
X03756Y03272*
X03751Y03276*
X03744Y03277*
G37*
G36*
X02259D02*
X02253Y03276D01*
X02248Y03272*
X02244Y03267*
X02243Y03261*
X02244Y03254*
X02248Y03249*
X02253Y03245*
X02259Y03244*
X02266Y03245*
X02271Y03249*
X02274Y03254*
X02276Y03261*
X02274Y03267*
X02271Y03272*
X02266Y03276*
X02259Y03277*
G37*
G36*
X0323Y03251D02*
X03224Y0325D01*
X03219Y03246*
X03215Y03241*
X03214Y03235*
X03215Y03228*
X03219Y03223*
X03224Y03219*
X0323Y03218*
X03237Y03219*
X03242Y03223*
X03245Y03228*
X03247Y03235*
X03245Y03241*
X03242Y03246*
X03237Y0325*
X0323Y03251*
G37*
G36*
X06282Y03242D02*
X06276Y03241D01*
X0627Y03237*
X06267Y03232*
X06266Y03226*
X06267Y03219*
X0627Y03214*
X06276Y0321*
X06282Y03209*
X06288Y0321*
X06293Y03214*
X06297Y03219*
X06298Y03226*
X06297Y03232*
X06293Y03237*
X06288Y03241*
X06282Y03242*
G37*
G36*
X03806Y03251D02*
X038Y0325D01*
X03795Y03246*
X03791Y03241*
X0379Y03235*
X03791Y03228*
X03795Y03223*
X03797Y03222*
X03796Y03216*
X03793Y03216*
X03788Y03212*
X03784Y03207*
X03783Y03201*
X03784Y03194*
X03788Y03189*
X03793Y03185*
X03799Y03184*
X03806Y03185*
X03811Y03189*
X03814Y03194*
X03816Y03201*
X03814Y03207*
X03811Y03212*
X03809Y03214*
X0381Y03219*
X03813Y03219*
X03818Y03223*
X03821Y03228*
X03823Y03235*
X03821Y03241*
X03818Y03246*
X03813Y0325*
X03806Y03251*
G37*
G36*
X02205Y03216D02*
X02199Y03215D01*
X02194Y03211*
X0219Y03206*
X02189Y032*
X0219Y03193*
X02194Y03188*
X02199Y03184*
X02205Y03183*
X02212Y03184*
X02217Y03188*
X0222Y03193*
X02222Y032*
X0222Y03206*
X02217Y03211*
X02212Y03215*
X02205Y03216*
G37*
G36*
X02422Y03263D02*
X02413Y03261D01*
X02405Y03256*
X024Y03248*
X02398Y03239*
X024Y0323*
X02405Y03223*
X02409Y0322*
X02408Y03215*
X02407Y03214*
X02402Y03211*
X02398Y03206*
X02397Y03199*
X02398Y03193*
X02402Y03188*
X02407Y03184*
X02414Y03183*
X0242Y03184*
X02425Y03188*
X02429Y03193*
X0243Y03199*
X02429Y03206*
X02425Y03211*
X02425Y03211*
X02426Y03217*
X02431Y03218*
X02438Y03223*
X02443Y0323*
X02445Y03239*
X02443Y03248*
X02438Y03256*
X02431Y03261*
X02422Y03263*
G37*
G36*
X06309Y03215D02*
X06303Y03214D01*
X06297Y0321*
X06294Y03205*
X06293Y03199*
X06294Y03192*
X06297Y03187*
X06303Y03183*
X06309Y03182*
X06315Y03183*
X0632Y03187*
X06324Y03192*
X06325Y03199*
X06324Y03205*
X0632Y0321*
X06315Y03214*
X06309Y03215*
G37*
G36*
X06439Y03207D02*
X06433Y03206D01*
X06428Y03202*
X06424Y03197*
X06423Y03191*
X06424Y03184*
X06428Y03179*
X06433Y03175*
X06439Y03174*
X06446Y03175*
X06451Y03179*
X06454Y03184*
X06456Y03191*
X06454Y03197*
X06451Y03202*
X06446Y03206*
X06439Y03207*
G37*
G36*
X03188Y03203D02*
X03182Y03202D01*
X03177Y03198*
X03173Y03193*
X03172Y03187*
X03173Y0318*
X03177Y03175*
X03182Y03171*
X03188Y0317*
X03195Y03171*
X032Y03175*
X03204Y0318*
X03205Y03187*
X03204Y03193*
X032Y03198*
X03195Y03202*
X03188Y03203*
G37*
G36*
X02591Y03202D02*
X02585Y03201D01*
X0258Y03197*
X02576Y03192*
X02575Y03186*
X02576Y03179*
X0258Y03174*
X02585Y03171*
X02591Y03169*
X02598Y03171*
X02603Y03174*
X02606Y03179*
X02608Y03186*
X02606Y03192*
X02603Y03197*
X02598Y03201*
X02591Y03202*
G37*
G36*
X02462Y03188D02*
X02456Y03187D01*
X0245Y03183*
X02447Y03178*
X02446Y03172*
X02447Y03166*
X0245Y0316*
X02456Y03157*
X02462Y03155*
X02468Y03157*
X02473Y0316*
X02477Y03166*
X02478Y03172*
X02477Y03178*
X02473Y03183*
X02468Y03187*
X02462Y03188*
G37*
G36*
X06339Y03167D02*
X06333Y03166D01*
X06328Y03162*
X06324Y03157*
X06323Y03151*
X06324Y03144*
X06328Y03139*
X06333Y03135*
X06339Y03134*
X06346Y03135*
X06351Y03139*
X06354Y03144*
X06356Y03151*
X06354Y03157*
X06351Y03162*
X06346Y03166*
X06339Y03167*
G37*
G36*
X03829Y03192D02*
X03823Y03191D01*
X03818Y03187*
X03814Y03182*
X03813Y03176*
X03814Y03169*
X03818Y03164*
X03823Y0316*
X03829Y03159*
X03836Y0316*
X03836Y03161*
X03839Y03157*
X03839Y03157*
X03838Y03151*
X03839Y03144*
X03843Y03139*
X03848Y03135*
X03854Y03134*
X03861Y03135*
X03866Y03139*
X03869Y03144*
X03871Y03151*
X03869Y03157*
X03866Y03162*
X03861Y03166*
X03854Y03167*
X03848Y03166*
X03848Y03165*
X03844Y03169*
X03844Y03169*
X03846Y03176*
X03844Y03182*
X03841Y03187*
X03836Y03191*
X03829Y03192*
G37*
G36*
X01459Y03163D02*
X01453Y03162D01*
X01448Y03158*
X01444Y03153*
X01443Y03147*
X01444Y0314*
X01448Y03135*
X01453Y03131*
X01459Y0313*
X01466Y03131*
X01471Y03135*
X01474Y0314*
X01476Y03147*
X01474Y03153*
X01471Y03158*
X01466Y03162*
X01459Y03163*
G37*
G36*
X03275Y03158D02*
X03269Y03156D01*
X03264Y03153*
X0326Y03147*
X03259Y03141*
X0326Y03135*
X03264Y0313*
X03269Y03126*
X03275Y03125*
X03281Y03126*
X03287Y0313*
X0329Y03135*
X03291Y03141*
X0329Y03147*
X03287Y03153*
X03281Y03156*
X03275Y03158*
G37*
G36*
X06304Y03137D02*
X06298Y03136D01*
X06293Y03132*
X06289Y03127*
X06288Y03121*
X06289Y03114*
X06293Y03109*
X06298Y03105*
X06304Y03104*
X06311Y03105*
X06316Y03109*
X06319Y03114*
X06321Y03121*
X06319Y03127*
X06316Y03132*
X06311Y03136*
X06304Y03137*
G37*
G36*
X03939D02*
X03933Y03136D01*
X03928Y03132*
X03924Y03127*
X03923Y03121*
X03924Y03114*
X03928Y03109*
X03933Y03105*
X03939Y03104*
X03946Y03105*
X03951Y03109*
X03954Y03114*
X03956Y03121*
X03954Y03127*
X03951Y03132*
X03946Y03136*
X03939Y03137*
G37*
G36*
X03491Y03119D02*
X03485Y03118D01*
X0348Y03114*
X03476Y03109*
X03475Y03103*
X03476Y03096*
X0348Y03091*
X03485Y03087*
X03491Y03086*
X03498Y03087*
X03503Y03091*
X03506Y03096*
X03508Y03103*
X03506Y03109*
X03503Y03114*
X03498Y03118*
X03491Y03119*
G37*
G36*
X02418Y03134D02*
X02412Y03133D01*
X02407Y0313*
X02403Y03124*
X02402Y03118*
X02403Y03112*
X02407Y03106*
X02408Y03106*
Y031*
X02405Y03098*
X024Y03091*
X02398Y03082*
X024Y03073*
X02405Y03065*
X02413Y0306*
X02422Y03058*
X02431Y0306*
X02438Y03065*
X02443Y03073*
X02445Y03082*
X02443Y03091*
X02438Y03098*
X02432Y03102*
X02431Y03105*
X02431Y03108*
X02433Y03112*
X02435Y03118*
X02433Y03124*
X0243Y0313*
X02424Y03133*
X02418Y03134*
G37*
G36*
X03368Y03066D02*
X03362Y03065D01*
X03357Y03061*
X03353Y03056*
X03352Y0305*
X03353Y03043*
X03357Y03038*
X03362Y03034*
X03368Y03033*
X03375Y03034*
X0338Y03038*
X03383Y03043*
X03385Y0305*
X03383Y03056*
X0338Y03061*
X03375Y03065*
X03368Y03066*
G37*
G36*
X03344Y03012D02*
X03338Y03011D01*
X03333Y03007*
X03329Y03002*
X03328Y02996*
X03329Y02989*
X03333Y02984*
X03338Y0298*
X03344Y02979*
X03351Y0298*
X03356Y02984*
X03359Y02989*
X03361Y02996*
X03359Y03002*
X03356Y03007*
X03351Y03011*
X03344Y03012*
G37*
G36*
X03197Y02986D02*
X03191Y02985D01*
X03186Y02981*
X03182Y02976*
X03181Y0297*
X03182Y02963*
X03186Y02958*
X03191Y02954*
X03197Y02953*
X03204Y02954*
X03209Y02958*
X03212Y02963*
X03214Y0297*
X03212Y02976*
X03209Y02981*
X03204Y02985*
X03197Y02986*
G37*
G36*
X04794Y02824D02*
X04788Y02823D01*
X04782Y02819*
X04779Y02814*
X04777Y02808*
X04779Y02801*
X04782Y02796*
X04788Y02793*
X04794Y02791*
X048Y02793*
X04805Y02796*
X04809Y02801*
X0481Y02808*
X04809Y02814*
X04805Y02819*
X048Y02823*
X04794Y02824*
G37*
G36*
X04503Y02806D02*
X04497Y02804D01*
X04492Y02801*
X04488Y02796*
X04487Y02789*
X04488Y02783*
X04492Y02778*
X04497Y02774*
X04503Y02773*
X04509Y02774*
X04515Y02778*
X04518Y02783*
X04519Y02789*
X04518Y02796*
X04515Y02801*
X04509Y02804*
X04503Y02806*
G37*
G36*
X02146Y02769D02*
X0214Y02768D01*
X02135Y02764*
X02131Y02759*
X0213Y02753*
X02131Y02746*
X02135Y02741*
X0214Y02737*
X02146Y02736*
X02153Y02737*
X02158Y02741*
X02161Y02746*
X02163Y02753*
X02161Y02759*
X02158Y02764*
X02153Y02768*
X02146Y02769*
G37*
G36*
X02692Y02737D02*
X02686Y02736D01*
X02681Y02732*
X02677Y02727*
X02676Y02721*
X02677Y02715*
X02681Y02709*
X02686Y02706*
X02692Y02705*
X02699Y02706*
X02704Y02709*
X02707Y02715*
X02709Y02721*
X02707Y02727*
X02704Y02732*
X02699Y02736*
X02692Y02737*
G37*
G36*
X02394Y02736D02*
X02388Y02735D01*
X02383Y02732*
X02379Y02726*
X02378Y0272*
X02379Y02714*
X02383Y02708*
X02388Y02705*
X02394Y02704*
X024Y02705*
X02406Y02708*
X02409Y02714*
X02411Y0272*
X02409Y02726*
X02406Y02732*
X024Y02735*
X02394Y02736*
G37*
G36*
X02494Y02712D02*
X02488Y02711D01*
X02483Y02707*
X02479Y02702*
X02478Y02696*
X02479Y02689*
X02483Y02684*
X02488Y02681*
X02488Y02679*
Y02678*
X02488Y02675*
X02483Y02672*
X02479Y02667*
X02478Y02661*
X02479Y02654*
X02483Y02649*
X02488Y02645*
X02494Y02644*
X02501Y02645*
X02506Y02649*
X02509Y02654*
X02511Y02661*
X02509Y02667*
X02506Y02672*
X02501Y02675*
X02501Y02678*
Y02679*
X02501Y02681*
X02506Y02684*
X02509Y02689*
X02511Y02696*
X02509Y02702*
X02506Y02707*
X02501Y02711*
X02494Y02712*
G37*
G36*
X02958Y02637D02*
X02952Y02636D01*
X02947Y02632*
X02943Y02627*
X02942Y02621*
X02943Y02614*
X02947Y02609*
X02952Y02605*
X02958Y02604*
X02965Y02605*
X0297Y02609*
X02973Y02614*
X02975Y02621*
X02973Y02627*
X0297Y02632*
X02965Y02636*
X02958Y02637*
G37*
G36*
X02429D02*
X02422Y02636D01*
X02417Y02632*
X02414Y02627*
X02412Y02621*
X02414Y02614*
X02417Y02609*
X02422Y02605*
X02429Y02604*
X02435Y02605*
X0244Y02609*
X02444Y02614*
X02445Y02621*
X02444Y02627*
X0244Y02632*
X02435Y02636*
X02429Y02637*
G37*
G36*
X02252Y02629D02*
X02246Y02628D01*
X0224Y02625*
X02237Y02619*
X02236Y02613*
X02237Y02607*
X02239Y02603*
X02236Y02599*
X02231Y026*
X02225Y02599*
X0222Y02595*
X02216Y0259*
X02215Y02584*
X02216Y02577*
X0222Y02572*
X02225Y02569*
X02231Y02567*
X02237Y02569*
X02243Y02572*
X02246Y02577*
X02248Y02584*
X02246Y0259*
X02244Y02594*
X02247Y02598*
X02252Y02597*
X02258Y02598*
X02263Y02602*
X02267Y02607*
X02268Y02613*
X02267Y02619*
X02263Y02625*
X02258Y02628*
X02252Y02629*
G37*
G36*
X02821Y02617D02*
X02815Y02616D01*
X0281Y02612*
X02806Y02607*
X02805Y02601*
X02806Y02594*
X0281Y02589*
X02815Y02585*
X02821Y02584*
X02828Y02585*
X02833Y02589*
X02836Y02594*
X02838Y02601*
X02836Y02607*
X02833Y02612*
X02828Y02616*
X02821Y02617*
G37*
G36*
X03623Y02603D02*
X03617Y02602D01*
X03612Y02598*
X03608Y02593*
X03607Y02587*
X03608Y0258*
X03612Y02575*
X03617Y02571*
X03623Y0257*
X0363Y02571*
X03635Y02575*
X03638Y0258*
X0364Y02587*
X03638Y02593*
X03635Y02598*
X0363Y02602*
X03623Y02603*
G37*
G36*
X04298Y02641D02*
X04286Y02639D01*
X04275Y02635*
X04266Y02627*
X04258Y02618*
X04254Y02607*
X04252Y02595*
X04254Y02583*
X04258Y02572*
X04266Y02562*
X04275Y02555*
X04286Y02551*
X04298Y02549*
X0431Y02551*
X04321Y02555*
X04331Y02562*
X04338Y02572*
X04342Y02583*
X04344Y02595*
X04342Y02607*
X04338Y02618*
X04331Y02627*
X04321Y02635*
X0431Y02639*
X04298Y02641*
G37*
G36*
X0418D02*
X04168Y02639D01*
X04157Y02635*
X04148Y02627*
X0414Y02618*
X04136Y02607*
X04134Y02595*
X04136Y02583*
X0414Y02572*
X04148Y02562*
X04157Y02555*
X04168Y02551*
X0418Y02549*
X04192Y02551*
X04203Y02555*
X04212Y02562*
X0422Y02572*
X04224Y02583*
X04226Y02595*
X04224Y02607*
X0422Y02618*
X04212Y02627*
X04203Y02635*
X04192Y02639*
X0418Y02641*
G37*
G36*
X04062D02*
X0405Y02639D01*
X04039Y02635*
X04029Y02627*
X04022Y02618*
X04018Y02607*
X04016Y02595*
X04018Y02583*
X04022Y02572*
X04029Y02562*
X04039Y02555*
X0405Y02551*
X04062Y02549*
X04074Y02551*
X04085Y02555*
X04094Y02562*
X04102Y02572*
X04106Y02583*
X04108Y02595*
X04106Y02607*
X04102Y02618*
X04094Y02627*
X04085Y02635*
X04074Y02639*
X04062Y02641*
G37*
G36*
X06284Y02517D02*
X06278Y02516D01*
X06273Y02512*
X06269Y02507*
X06268Y02501*
X06269Y02494*
X06273Y02489*
X06278Y02485*
X06284Y02484*
X06291Y02485*
X06296Y02489*
X06299Y02494*
X06301Y02501*
X06299Y02507*
X06296Y02512*
X06291Y02516*
X06284Y02517*
G37*
G36*
X0102Y02497D02*
X01014Y02496D01*
X01009Y02492*
X01005Y02487*
X01004Y02481*
X01005Y02474*
X01009Y02469*
X01014Y02465*
X0102Y02464*
X01027Y02465*
X01032Y02469*
X01035Y02474*
X01037Y02481*
X01035Y02487*
X01032Y02492*
X01027Y02496*
X0102Y02497*
G37*
G36*
X02624Y02477D02*
X02618Y02476D01*
X02613Y02472*
X02609Y02467*
X02608Y02461*
X02609Y02454*
X02609Y02454*
X02606Y0245*
X02606Y02451*
X02599Y02452*
X02593Y02451*
X02588Y02447*
X02584Y02442*
X02583Y02436*
X02584Y02431*
X02583Y0243*
X02581Y02427*
X0258Y02427*
X02575Y02428*
X02569Y02427*
X02564Y02423*
X0256Y02418*
X02559Y02412*
X0256Y02405*
X02564Y024*
X02569Y02396*
X02575Y02395*
X02582Y02396*
X02587Y024*
X0259Y02405*
X02592Y02412*
X02591Y02416*
X02591Y02417*
X02594Y0242*
X02595Y0242*
X02599Y02419*
X02606Y0242*
X02611Y02424*
X02614Y02429*
X02616Y02436*
X02614Y02442*
X02614Y02442*
X02618Y02446*
X02618Y02445*
X02624Y02444*
X02631Y02445*
X02636Y02449*
X02639Y02454*
X02641Y02461*
X02639Y02467*
X02636Y02472*
X02631Y02476*
X02624Y02477*
G37*
G36*
X02272Y0248D02*
X02265Y02478D01*
X0226Y02475*
X02256Y0247*
X02255Y02463*
X02256Y02457*
X0226Y02452*
X02265Y02448*
X02272Y02447*
X02278Y02448*
X02283Y02452*
X02287Y02457*
X02288Y02463*
X02287Y0247*
X02283Y02475*
X02278Y02478*
X02272Y0248*
G37*
G36*
X02525Y02479D02*
X02519Y02478D01*
X02514Y02474*
X0251Y02469*
X02509Y02463*
X0251Y02456*
X02514Y02451*
X02519Y02447*
X02525Y02446*
X02532Y02447*
X02537Y02451*
X0254Y02456*
X02542Y02463*
X0254Y02469*
X02537Y02474*
X02532Y02478*
X02525Y02479*
G37*
G36*
X05578Y02534D02*
X05566Y02533D01*
X05555Y02528*
X05545Y02521*
X05538Y02511*
X05533Y025*
X05532Y02489*
X05533Y02477*
X05538Y02466*
X05545Y02456*
X05555Y02449*
X05566Y02444*
X05578Y02443*
X0559Y02444*
X05601Y02449*
X0561Y02456*
X05617Y02466*
X05622Y02477*
X05624Y02489*
X05622Y025*
X05617Y02511*
X0561Y02521*
X05601Y02528*
X0559Y02533*
X05578Y02534*
G37*
G36*
X02948Y02472D02*
X02942Y02471D01*
X02937Y02467*
X02933Y02462*
X02932Y02456*
X02933Y02449*
X02937Y02444*
X02942Y0244*
X02948Y02439*
X02955Y0244*
X0296Y02444*
X02963Y02449*
X02965Y02456*
X02963Y02462*
X0296Y02467*
X02955Y02471*
X02948Y02472*
G37*
G36*
X0299Y02457D02*
X02983Y02456D01*
X02976Y02452*
X02972Y02445*
X02971Y02438*
X02972Y02431*
X02976Y02424*
X02983Y0242*
X0299Y02419*
X02997Y0242*
X03004Y02424*
X03008Y02431*
X03009Y02438*
X03008Y02445*
X03004Y02452*
X02997Y02456*
X0299Y02457*
G37*
G36*
X02203D02*
X02195Y02456D01*
X02189Y02452*
X02185Y02445*
X02183Y02438*
X02185Y02431*
X02189Y02424*
X02195Y0242*
X02203Y02419*
X0221Y0242*
X02216Y02424*
X0222Y02431*
X02222Y02438*
X0222Y02445*
X02216Y02452*
X0221Y02456*
X02203Y02457*
G37*
G36*
X03617Y02553D02*
X03604Y02552D01*
X03592Y02548*
X0358Y02542*
X0357Y02533*
X03561Y02523*
X03555Y02512*
X03551Y02499*
X0355Y02486*
X03551Y02473*
X03555Y0246*
X03561Y02448*
X0357Y02438*
X0358Y0243*
X03592Y02424*
X03604Y0242*
X03617Y02418*
X03631Y0242*
X03643Y02424*
X03655Y0243*
X03665Y02438*
X03673Y02448*
X0368Y0246*
X03684Y02473*
X03685Y02486*
X03684Y02499*
X0368Y02512*
X03673Y02523*
X03665Y02533*
X03655Y02542*
X03643Y02548*
X03631Y02552*
X03617Y02553*
G37*
G36*
X01651D02*
X01638Y02552D01*
X01626Y02548*
X01614Y02542*
X01604Y02533*
X01595Y02523*
X01589Y02512*
X01585Y02499*
X01584Y02486*
X01585Y02473*
X01589Y0246*
X01595Y02448*
X01604Y02438*
X01614Y0243*
X01626Y02424*
X01638Y0242*
X01651Y02418*
X01665Y0242*
X01677Y02424*
X01689Y0243*
X01699Y02438*
X01707Y02448*
X01714Y0246*
X01718Y02473*
X01719Y02486*
X01718Y02499*
X01714Y02512*
X01707Y02523*
X01699Y02533*
X01689Y02542*
X01677Y02548*
X01665Y02552*
X01651Y02553*
G37*
G36*
X00199Y02545D02*
X00187Y02544D01*
X00175Y0254*
X00164Y02534*
X00154Y02526*
X00146Y02516*
X0014Y02505*
X00136Y02493*
X00135Y02481*
X00136Y02468*
X0014Y02456*
X00146Y02445*
X00154Y02435*
X00164Y02427*
X00175Y02421*
X00187Y02417*
X00199Y02416*
X00212Y02417*
X00224Y02421*
X00235Y02427*
X00245Y02435*
X00253Y02445*
X00259Y02456*
X00262Y02468*
X00264Y02481*
X00262Y02493*
X00259Y02505*
X00253Y02516*
X00245Y02526*
X00235Y02534*
X00224Y0254*
X00212Y02544*
X00199Y02545*
G37*
G36*
X02894Y02447D02*
X02888Y02446D01*
X02883Y02442*
X02879Y02437*
X02878Y02431*
X02879Y02424*
X02883Y02419*
X02888Y02415*
X02894Y02414*
X02901Y02415*
X02906Y02419*
X02907*
X02909Y02416*
X02914Y02412*
X0292Y02411*
X02927Y02412*
X02932Y02416*
X02935Y02421*
X02937Y02428*
X02935Y02434*
X02932Y02439*
X02927Y02443*
X0292Y02444*
X02914Y02443*
X02909Y02439*
X02908*
X02906Y02442*
X02901Y02446*
X02894Y02447*
G37*
G36*
X04039Y02422D02*
X04033Y02421D01*
X04028Y02417*
X04024Y02412*
X04023Y02406*
X04024Y02399*
X04028Y02394*
X04033Y0239*
X04039Y02389*
X04046Y0239*
X04051Y02394*
X04054Y02399*
X04056Y02406*
X04054Y02412*
X04051Y02417*
X04046Y02421*
X04039Y02422*
G37*
G36*
X03498Y02357D02*
X03492Y02356D01*
X03487Y02352*
X03483Y02347*
X03482Y02341*
X03483Y02334*
X03487Y02329*
X03492Y02325*
X03498Y02324*
X03505Y02325*
X0351Y02329*
X03513Y02334*
X03515Y02341*
X03513Y02347*
X0351Y02352*
X03505Y02356*
X03498Y02357*
G37*
G36*
X02726Y02309D02*
X0272Y02308D01*
X02715Y02304*
X02713Y02301*
X02709Y02304*
X02702Y02305*
X02696Y02304*
X02691Y023*
X02687Y02295*
X02686Y0229*
X02682Y02291*
X0268Y02297*
X02677Y02302*
X02672Y02306*
X02665Y02307*
X02659Y02306*
X02654Y02302*
X0265Y02297*
X02649Y02291*
X02648Y02289*
X02645Y0229*
X02639Y02289*
X02634Y02285*
X0263Y0228*
X02629Y02274*
X0263Y02267*
X02634Y02262*
X02639Y02258*
X02645Y02257*
X02652Y02258*
X02657Y02262*
X0266Y02267*
X02662Y02274*
X02663Y02275*
X02665Y02274*
X02672Y02275*
X02677Y02279*
X0268Y02284*
X02681Y02289*
X02686Y02289*
X02687Y02282*
X02691Y02277*
X02696Y02273*
X02702Y02272*
X02709Y02273*
X02714Y02277*
X02716Y0228*
X0272Y02277*
X02726Y02276*
X02733Y02277*
X02738Y02281*
X02741Y02286*
X02743Y02293*
X02741Y02299*
X02738Y02304*
X02733Y02308*
X02726Y02309*
G37*
G36*
X02475Y02307D02*
X02469Y02306D01*
X02464Y02302*
X02462Y02299*
X02457Y02297*
X02455Y02297*
X0245Y02298*
X02444Y02297*
X02439Y02293*
X02435Y02288*
X02434Y02282*
X02435Y02275*
X02439Y0227*
X02444Y02266*
X0245Y02265*
X02457Y02266*
X02462Y0227*
X02465Y02275*
X0247Y02275*
X02475Y02274*
X02482Y02275*
X02487Y02279*
X0249Y02284*
X02492Y02291*
X0249Y02297*
X02487Y02302*
X02482Y02306*
X02475Y02307*
G37*
G36*
X02803Y02323D02*
X02797Y02322D01*
X02792Y02318*
X02788Y02313*
X02787Y02307*
X02788Y023*
X02792Y02295*
X02797Y02291*
X02803Y0229*
X0281Y02291*
X02815Y02295*
X02818Y023*
X0282Y02307*
X02818Y02313*
X02815Y02318*
X0281Y02322*
X02803Y02323*
G37*
G36*
X02985Y02303D02*
X02979Y02302D01*
X02974Y02298*
X0297Y02293*
X02969Y02287*
X0297Y0228*
X02974Y02275*
X02979Y02271*
X02985Y0227*
X02992Y02271*
X02997Y02275*
X03Y0228*
X03002Y02287*
X03Y02293*
X02997Y02298*
X02992Y02302*
X02985Y02303*
G37*
G36*
X02942Y02302D02*
X02936Y02301D01*
X02931Y02297*
X02927Y02292*
X02926Y02286*
X02927Y02279*
X02931Y02274*
X02936Y0227*
X02942Y02269*
X02949Y0227*
X02954Y02274*
X02957Y02279*
X02959Y02286*
X02957Y02292*
X02954Y02297*
X02949Y02301*
X02942Y02302*
G37*
G36*
X05327Y02346D02*
X05317Y02345D01*
X05308Y02341*
X053Y02334*
X05294Y02326*
X0529Y02317*
X05288Y02307*
X0529Y02297*
X05294Y02288*
X053Y0228*
X05308Y02273*
X05317Y02269*
X05327Y02268*
X05337Y02269*
X05347Y02273*
X05355Y0228*
X05361Y02288*
X05365Y02297*
X05366Y02307*
X05365Y02317*
X05361Y02326*
X05355Y02334*
X05347Y02341*
X05337Y02345*
X05327Y02346*
G37*
G36*
X04927D02*
X04917Y02345D01*
X04908Y02341*
X049Y02334*
X04894Y02326*
X0489Y02317*
X04888Y02307*
X0489Y02297*
X04894Y02288*
X049Y0228*
X04908Y02273*
X04917Y02269*
X04927Y02268*
X04937Y02269*
X04947Y02273*
X04955Y0228*
X04961Y02288*
X04965Y02297*
X04966Y02307*
X04965Y02317*
X04961Y02326*
X04955Y02334*
X04947Y02341*
X04937Y02345*
X04927Y02346*
G37*
G36*
X04727D02*
X04717Y02345D01*
X04708Y02341*
X047Y02334*
X04694Y02326*
X0469Y02317*
X04688Y02307*
X0469Y02297*
X04694Y02288*
X047Y0228*
X04708Y02273*
X04717Y02269*
X04727Y02268*
X04737Y02269*
X04747Y02273*
X04755Y0228*
X04761Y02288*
X04765Y02297*
X04766Y02307*
X04765Y02317*
X04761Y02326*
X04755Y02334*
X04747Y02341*
X04737Y02345*
X04727Y02346*
G37*
G36*
X04327D02*
X04317Y02345D01*
X04308Y02341*
X043Y02334*
X04294Y02326*
X0429Y02317*
X04288Y02307*
X0429Y02297*
X04294Y02288*
X043Y0228*
X04308Y02273*
X04317Y02269*
X04327Y02268*
X04337Y02269*
X04347Y02273*
X04355Y0228*
X04361Y02288*
X04365Y02297*
X04366Y02307*
X04365Y02317*
X04361Y02326*
X04355Y02334*
X04347Y02341*
X04337Y02345*
X04327Y02346*
G37*
G36*
X02409Y0233D02*
X02403Y02329D01*
X02398Y02325*
X02394Y0232*
X02393Y02314*
X02394Y02307*
X02398Y02302*
X02399Y02301*
Y02295*
X02398Y02294*
X02394Y02289*
X02393Y02283*
X02394Y02276*
X02398Y02271*
X02403Y02267*
X02409Y02266*
X02416Y02267*
X02421Y02271*
X02424Y02276*
X02426Y02283*
X02424Y02289*
X02421Y02294*
X02419Y02295*
Y02301*
X02421Y02302*
X02424Y02307*
X02426Y02314*
X02424Y0232*
X02421Y02325*
X02416Y02329*
X02409Y0233*
G37*
G36*
X02579Y02297D02*
X02573Y02296D01*
X02568Y02292*
X02564Y02287*
X02563Y02281*
X02564Y02274*
X02568Y02269*
X02573Y02265*
X02579Y02264*
X02586Y02265*
X02591Y02269*
X02594Y02274*
X02596Y02281*
X02594Y02287*
X02591Y02292*
X02586Y02296*
X02579Y02297*
G37*
G36*
X03342Y02279D02*
X03336Y02278D01*
X03331Y02274*
X03327Y02269*
X03326Y02263*
X03327Y02256*
X03331Y02251*
X03336Y02247*
X03342Y02246*
X03349Y02247*
X03354Y02251*
X03357Y02256*
X03359Y02263*
X03357Y02269*
X03354Y02274*
X03349Y02278*
X03342Y02279*
G37*
G36*
X02841D02*
X02835Y02278D01*
X0283Y02274*
X02826Y02269*
X02825Y02263*
X02826Y02256*
X0283Y02251*
X02835Y02247*
X02841Y02246*
X02848Y02247*
X02853Y02251*
X02856Y02256*
X02858Y02263*
X02856Y02269*
X02853Y02274*
X02848Y02278*
X02841Y02279*
G37*
G36*
X00996Y02272D02*
X0099Y02271D01*
X00985Y02267*
X00981Y02262*
X0098Y02256*
X00981Y02249*
X00985Y02244*
X0099Y0224*
X00996Y02239*
X01003Y0224*
X01008Y02244*
X01011Y02249*
X01013Y02256*
X01011Y02262*
X01008Y02267*
X01003Y02271*
X00996Y02272*
G37*
G36*
X05634Y02252D02*
X05628Y02251D01*
X05623Y02247*
X05619Y02242*
X05618Y02236*
X05619Y02229*
X05623Y02224*
X05628Y0222*
X05634Y02219*
X05641Y0222*
X05646Y02224*
X05649Y02229*
X05651Y02236*
X05649Y02242*
X05646Y02247*
X05641Y02251*
X05634Y02252*
G37*
G36*
X02499D02*
X02493Y02251D01*
X02488Y02247*
X02484Y02242*
X02483Y02236*
X02484Y02229*
X02488Y02224*
X02493Y0222*
X02499Y02219*
X02506Y0222*
X02511Y02224*
X02514Y02229*
X02516Y02236*
X02514Y02242*
X02511Y02247*
X02506Y02251*
X02499Y02252*
G37*
G36*
X0233Y02231D02*
X02324Y0223D01*
X02319Y02226*
X02315Y02221*
X02314Y02215*
X02315Y02208*
X02319Y02203*
X02324Y02199*
X0233Y02198*
X02337Y02199*
X02342Y02203*
X02345Y02208*
X02347Y02215*
X02345Y02221*
X02342Y02226*
X02337Y0223*
X0233Y02231*
G37*
G36*
X05577Y0223D02*
X05571Y02229D01*
X05566Y02225*
X05562Y0222*
X05561Y02214*
X05562Y02207*
X05566Y02202*
X05571Y02198*
X05577Y02197*
X05584Y02198*
X05589Y02202*
X05592Y02207*
X05594Y02214*
X05592Y0222*
X05589Y02225*
X05584Y02229*
X05577Y0223*
G37*
G36*
X06424Y02197D02*
X06418Y02196D01*
X06413Y02192*
X06409Y02187*
X06408Y02181*
X06409Y02174*
X06413Y02169*
X06418Y02165*
X06424Y02164*
X06431Y02165*
X06436Y02169*
X06439Y02174*
X06441Y02181*
X06439Y02187*
X06436Y02192*
X06431Y02196*
X06424Y02197*
G37*
G36*
X01754Y02142D02*
X01748Y02141D01*
X01743Y02137*
X01739Y02132*
X01738Y02126*
X01739Y02119*
X01743Y02114*
X01748Y0211*
X01754Y02109*
X01761Y0211*
X01766Y02114*
X01769Y02119*
X01771Y02126*
X01769Y02132*
X01766Y02137*
X01761Y02141*
X01754Y02142*
G37*
G36*
X01619Y02137D02*
X01613Y02136D01*
X01608Y02132*
X01604Y02127*
X01603Y02121*
X01604Y02114*
X01608Y02109*
X01613Y02105*
X01619Y02104*
X01626Y02105*
X01631Y02109*
X01634Y02114*
X01636Y02121*
X01634Y02127*
X01631Y02132*
X01626Y02136*
X01619Y02137*
G37*
G36*
X01696Y02116D02*
X01689Y02114D01*
X01683Y0211*
X01679Y02104*
X01677Y02097*
X01679Y02089*
X01683Y02083*
X01689Y02079*
X01696Y02078*
X01704Y02079*
X0171Y02083*
X01714Y02089*
X01716Y02097*
X01714Y02104*
X0171Y0211*
X01704Y02114*
X01696Y02116*
G37*
G36*
X01884Y02087D02*
X01878Y02086D01*
X01873Y02082*
X01869Y02077*
X01868Y02071*
X01869Y02064*
X01873Y02059*
X01878Y02055*
X01884Y02054*
X01891Y02055*
X01896Y02059*
X01899Y02064*
X01901Y02071*
X01899Y02077*
X01896Y02082*
X01891Y02086*
X01884Y02087*
G37*
G36*
X01568Y02084D02*
X01561Y02082D01*
X01556Y02079*
X01553Y02073*
X01551Y02067*
X01553Y02061*
X01556Y02056*
X01561Y02052*
X01568Y02051*
X01574Y02052*
X01579Y02056*
X01583Y02061*
X01584Y02067*
X01583Y02073*
X01579Y02079*
X01574Y02082*
X01568Y02084*
G37*
G36*
X03571Y02116D02*
X03564Y02114D01*
X03558Y0211*
X03554Y02104*
X03552Y02097*
X03554Y02089*
X03558Y02083*
X03564Y02079*
X03568Y02078*
Y02073*
X03565Y02073*
X0356Y02069*
X03556Y02064*
X03555Y02058*
X03556Y02051*
X03558Y02049*
X03559Y02045*
X03558Y02041*
X03556Y02039*
X03555Y02033*
X03556Y02026*
X0356Y02021*
X03565Y02017*
X03571Y02016*
X03578Y02017*
X03583Y02021*
X03586Y02026*
X03588Y02033*
X03586Y02039*
X03585Y02041*
X03583Y02045*
X03585Y02049*
X03586Y02051*
X03588Y02058*
X03586Y02064*
X03583Y02069*
X03578Y02073*
X03575Y02073*
Y02078*
X03579Y02079*
X03585Y02083*
X03589Y02089*
X0359Y02097*
X03589Y02104*
X03585Y0211*
X03579Y02114*
X03571Y02116*
G37*
G36*
X02409Y01983D02*
X02403Y01982D01*
X02398Y01978*
X02394Y01973*
X02393Y01967*
X02394Y0196*
X02396Y01958*
X02392Y01955*
X02391Y01956*
X02384Y01957*
X02378Y01956*
X02373Y01952*
X02369Y01947*
X02368Y01941*
X02369Y01934*
X02373Y01929*
X02378Y01925*
X02384Y01924*
X02391Y01925*
X02396Y01929*
X02399Y01934*
X02401Y01941*
X02399Y01947*
X02398Y01949*
X02402Y01952*
X02403Y01951*
X02409Y0195*
X02416Y01951*
X02421Y01955*
X02424Y0196*
X02426Y01967*
X02424Y01973*
X02421Y01978*
X02416Y01982*
X02409Y01983*
G37*
G36*
X03298Y01987D02*
X03292Y01986D01*
X03287Y01982*
X03283Y01977*
X03282Y01971*
X03283Y01964*
X03287Y01959*
X03292Y01955*
X03298Y01954*
X03305Y01955*
X0331Y01959*
X03313Y01964*
X03315Y01971*
X03313Y01977*
X0331Y01982*
X03305Y01986*
X03298Y01987*
G37*
G36*
X01009Y01972D02*
X01003Y01971D01*
X00998Y01967*
X00994Y01962*
X00993Y01956*
X00994Y01949*
X00998Y01944*
X01003Y0194*
X01009Y01939*
X01016Y0194*
X01021Y01944*
X01024Y01949*
X01026Y01956*
X01024Y01962*
X01021Y01967*
X01016Y01971*
X01009Y01972*
G37*
G36*
X02299Y01932D02*
X02293Y01931D01*
X02288Y01927*
X02284Y01922*
X02283Y01916*
X02284Y01909*
X02288Y01904*
X02293Y019*
X02299Y01899*
X02306Y019*
X02311Y01904*
X02314Y01909*
X02316Y01916*
X02314Y01922*
X02311Y01927*
X02306Y01931*
X02299Y01932*
G37*
G36*
X00199Y0202D02*
X00187Y02019D01*
X00175Y02015*
X00164Y02009*
X00154Y02001*
X00146Y01991*
X0014Y0198*
X00136Y01968*
X00135Y01956*
X00136Y01943*
X0014Y01931*
X00146Y0192*
X00154Y0191*
X00164Y01902*
X00175Y01896*
X00187Y01892*
X00199Y01891*
X00212Y01892*
X00224Y01896*
X00235Y01902*
X00245Y0191*
X00253Y0192*
X00259Y01931*
X00262Y01943*
X00264Y01956*
X00262Y01968*
X00259Y0198*
X00253Y01991*
X00245Y02001*
X00235Y02009*
X00224Y02015*
X00212Y02019*
X00199Y0202*
G37*
G36*
X03554Y01907D02*
X03548Y01906D01*
X03543Y01902*
X03539Y01897*
X03538Y01891*
X03539Y01884*
X03543Y01879*
X03548Y01875*
X03554Y01874*
X03561Y01875*
X03566Y01879*
X03569Y01884*
X03571Y01891*
X03569Y01897*
X03566Y01902*
X03561Y01906*
X03554Y01907*
G37*
G36*
X03392Y01887D02*
X03386Y01886D01*
X03381Y01882*
X03377Y01877*
X03376Y01871*
X03377Y01864*
X03381Y01859*
X03386Y01855*
X03392Y01854*
X03399Y01855*
X03404Y01859*
X03407Y01864*
X03409Y01871*
X03407Y01877*
X03404Y01882*
X03399Y01886*
X03392Y01887*
G37*
G36*
X03439Y01887D02*
X03433Y01886D01*
X03427Y01882*
X03424Y01877*
X03422Y0187*
X03424Y01864*
X03427Y01859*
X03433Y01855*
X03439Y01854*
X03445Y01855*
X0345Y01859*
X03454Y01864*
X03455Y0187*
X03454Y01877*
X0345Y01882*
X03445Y01886*
X03439Y01887*
G37*
G36*
X03804Y01856D02*
X03798Y01855D01*
X03793Y01851*
X03789Y01846*
X03788Y0184*
X03789Y01833*
X03793Y01828*
X03798Y01824*
X03804Y01823*
X03811Y01824*
X03816Y01828*
X03819Y01833*
X03821Y0184*
X03819Y01846*
X03816Y01851*
X03811Y01855*
X03804Y01856*
G37*
G36*
X03329Y01842D02*
X03322Y01841D01*
X03317Y01837*
X03314Y01832*
X03312Y01826*
X03314Y01819*
X03317Y01814*
X03322Y0181*
X03329Y01809*
X03335Y0181*
X0334Y01814*
X03344Y01819*
X03345Y01826*
X03344Y01832*
X0334Y01837*
X03335Y01841*
X03329Y01842*
G37*
G36*
X01393Y01833D02*
X01387Y01832D01*
X01382Y01828*
X01378Y01823*
X01377Y01816*
X01378Y0181*
X01382Y01805*
X01387Y01801*
X01393Y018*
X01399Y01801*
X01405Y01805*
X01408Y0181*
X0141Y01816*
X01408Y01823*
X01405Y01828*
X01399Y01832*
X01393Y01833*
G37*
G36*
X03944Y01832D02*
X03938Y01831D01*
X03933Y01827*
X03929Y01822*
X03928Y01816*
X03929Y01809*
X03933Y01804*
X03938Y018*
X03944Y01799*
X03951Y018*
X03956Y01804*
X03959Y01809*
X03961Y01816*
X03959Y01822*
X03956Y01827*
X03951Y01831*
X03944Y01832*
G37*
G36*
X03056Y01828D02*
X0305Y01826D01*
X03045Y01823*
X03041Y01818*
X0304Y01811*
X03041Y01805*
X03045Y018*
X0305Y01796*
X03056Y01795*
X03063Y01796*
X03068Y018*
X03071Y01805*
X03073Y01811*
X03071Y01818*
X03068Y01823*
X03063Y01826*
X03056Y01828*
G37*
G36*
X01879D02*
X01873Y01826D01*
X01868Y01823*
X01864Y01818*
X01863Y01811*
X01864Y01805*
X01868Y018*
X01873Y01796*
X01879Y01795*
X01886Y01796*
X01891Y018*
X01895Y01805*
X01896Y01811*
X01895Y01818*
X01891Y01823*
X01886Y01826*
X01879Y01828*
G37*
G36*
X04064Y01812D02*
X04058Y01811D01*
X04053Y01807*
X04049Y01802*
X04048Y01796*
X04049Y01789*
X04053Y01784*
X04058Y0178*
X04064Y01779*
X04071Y0178*
X04076Y01784*
X04079Y01789*
X04081Y01796*
X04079Y01802*
X04076Y01807*
X04071Y01811*
X04064Y01812*
G37*
G36*
X02579Y01806D02*
X02573Y01805D01*
X02568Y01801*
X02564Y01796*
X02563Y0179*
X02564Y01783*
X02568Y01778*
X02573Y01774*
X02579Y01773*
X02586Y01774*
X02591Y01778*
X02594Y01783*
X02596Y0179*
X02594Y01796*
X02591Y01801*
X02586Y01805*
X02579Y01806*
G37*
G36*
X02626Y01786D02*
X0262Y01785D01*
X02615Y01781*
X02611Y01776*
X0261Y0177*
X02611Y01763*
X02615Y01758*
X0262Y01754*
X02626Y01753*
X02633Y01754*
X02638Y01758*
X02641Y01763*
X02643Y0177*
X02641Y01776*
X02638Y01781*
X02633Y01785*
X02626Y01786*
G37*
G36*
X03719Y01782D02*
X03713Y01781D01*
X03708Y01777*
X03704Y01772*
X03703Y01766*
X03704Y01759*
X03708Y01754*
X03713Y0175*
X03719Y01749*
X03726Y0175*
X03731Y01754*
X03734Y01759*
X03736Y01766*
X03734Y01772*
X03731Y01777*
X03726Y01781*
X03719Y01782*
G37*
G36*
X02549Y01771D02*
X02543Y0177D01*
X02538Y01766*
X02534Y01761*
X02533Y01755*
X02534Y01748*
X02538Y01743*
X02543Y01739*
X02549Y01738*
X02556Y01739*
X02561Y01743*
X02564Y01748*
X02566Y01755*
X02564Y01761*
X02561Y01766*
X02556Y0177*
X02549Y01771*
G37*
G36*
X04134Y01767D02*
X04128Y01766D01*
X04123Y01762*
X04119Y01757*
X04118Y01751*
X04119Y01744*
X04123Y01739*
X04128Y01735*
X04134Y01734*
X04141Y01735*
X04146Y01739*
X04149Y01744*
X04151Y01751*
X04149Y01757*
X04146Y01762*
X04141Y01766*
X04134Y01767*
G37*
G36*
X02604Y0175D02*
X02598Y01749D01*
X02593Y01745*
X02589Y0174*
X02588Y01734*
X02589Y01727*
X02593Y01722*
X02598Y01718*
X02604Y01717*
X02611Y01718*
X02616Y01722*
X02619Y01727*
X02621Y01734*
X02619Y0174*
X02616Y01745*
X02611Y01749*
X02604Y0175*
G37*
G36*
X00988Y01733D02*
X00981Y01732D01*
X00976Y01729*
X00973Y01723*
X00971Y01717*
X00973Y01711*
X00976Y01705*
X00981Y01702*
X00988Y01701*
X00994Y01702*
X00999Y01705*
X01003Y01711*
X01004Y01717*
X01003Y01723*
X00999Y01729*
X00994Y01732*
X00988Y01733*
G37*
G36*
X03197Y0173D02*
X03191Y01729D01*
X03185Y01725*
X03182Y0172*
X0318Y01714*
X03182Y01707*
X03185Y01702*
X03191Y01698*
X03197Y01697*
X03203Y01698*
X03208Y01702*
X03212Y01707*
X03213Y01714*
X03212Y0172*
X03208Y01725*
X03203Y01729*
X03197Y0173*
G37*
G36*
X03589Y01727D02*
X03583Y01726D01*
X03578Y01722*
X03574Y01717*
X03573Y01711*
X03574Y01704*
X03578Y01699*
X03583Y01695*
X03589Y01694*
X03596Y01695*
X03601Y01699*
X03604Y01704*
X03606Y01711*
X03604Y01717*
X03601Y01722*
X03596Y01726*
X03589Y01727*
G37*
G36*
X01893Y01709D02*
X01887Y01708D01*
X01882Y01704*
X01878Y01699*
X01877Y01693*
X01878Y01686*
X01882Y01681*
X01887Y01677*
X01893Y01676*
X019Y01677*
X01905Y01681*
X01908Y01686*
X0191Y01693*
X01908Y01699*
X01905Y01704*
X019Y01708*
X01893Y01709*
G37*
G36*
X03803Y01707D02*
X03797Y01706D01*
X03792Y01702*
X03788Y01697*
X03787Y01691*
X03788Y01684*
X03792Y01679*
X03797Y01675*
X03803Y01674*
X0381Y01675*
X03815Y01679*
X03818Y01684*
X0382Y01691*
X03818Y01697*
X03815Y01702*
X0381Y01706*
X03803Y01707*
G37*
G36*
X03724Y01691D02*
X03718Y0169D01*
X03713Y01686*
X03709Y01681*
X03708Y01675*
X03709Y01668*
X03713Y01663*
X03718Y01659*
X03724Y01658*
X03731Y01659*
X03736Y01663*
X03739Y01668*
X03741Y01675*
X03739Y01681*
X03736Y01686*
X03731Y0169*
X03724Y01691*
G37*
G36*
X01822Y0169D02*
X01816Y01689D01*
X01811Y01685*
X01807Y0168*
X01806Y01674*
X01807Y01667*
X01811Y01662*
X01816Y01658*
X01822Y01657*
X01829Y01658*
X01834Y01662*
X01837Y01667*
X01839Y01674*
X01837Y0168*
X01834Y01685*
X01829Y01689*
X01822Y0169*
G37*
G36*
X03773Y01682D02*
X03767Y01681D01*
X03762Y01677*
X03758Y01672*
X03757Y01666*
X03758Y01659*
X03762Y01654*
X03767Y01651*
X03773Y01649*
X0378Y01651*
X03785Y01654*
X03788Y01659*
X0379Y01666*
X03788Y01672*
X03785Y01677*
X0378Y01681*
X03773Y01682*
G37*
G36*
X06844Y01677D02*
X06838Y01676D01*
X06833Y01672*
X06829Y01667*
X06828Y01661*
X06829Y01654*
X06833Y01649*
X06838Y01645*
X06844Y01644*
X06851Y01645*
X06856Y01649*
X06859Y01654*
X06861Y01661*
X06859Y01667*
X06856Y01672*
X06851Y01676*
X06844Y01677*
G37*
G36*
X03224Y01677D02*
X03218Y01676D01*
X03213Y01672*
X03209Y01667*
X03208Y01661*
X03209Y01655*
X03213Y01649*
X03218Y01646*
X03224Y01645*
X03231Y01646*
X03235Y01649*
X03239Y01649*
X03241Y01649*
X03246Y01645*
X03252Y01644*
X03259Y01645*
X03264Y01649*
X03267Y01654*
X03269Y01661*
X03267Y01667*
X03264Y01672*
X03259Y01676*
X03252Y01677*
X03246Y01676*
X03242Y01673*
X03238Y01672*
X03235Y01673*
X03231Y01676*
X03224Y01677*
G37*
G36*
X02666Y01656D02*
X0266Y01655D01*
X02655Y01651*
X02651Y01646*
X0265Y0164*
X02651Y01635*
X02647Y01631*
X02647Y01631*
X02643Y01632*
X02637Y01631*
X02632Y01627*
X02628Y01622*
X02627Y01616*
X02628Y01609*
X02632Y01604*
X02637Y016*
X02643Y01599*
X0265Y016*
X02655Y01604*
X02658Y01609*
X0266Y01616*
X02659Y0162*
X02662Y01624*
X02663Y01624*
X02666Y01623*
X02673Y01624*
X02678Y01628*
X02681Y01633*
X02683Y0164*
X02681Y01646*
X02678Y01651*
X02673Y01655*
X02666Y01656*
G37*
G36*
X04134Y01667D02*
X04128Y01666D01*
X04123Y01662*
X04119Y01657*
X04118Y01651*
X04119Y01644*
X04123Y01639*
X04128Y01635*
X04133Y01634*
X04135Y01631*
X04136Y01629*
X04136Y01629*
X04134Y01623*
X04136Y01617*
X04139Y01612*
X04145Y01608*
X04151Y01607*
X04157Y01608*
X04161Y01611*
X04164Y01607*
X04164Y01607*
X04163Y01601*
X04164Y01594*
X04168Y01589*
X04173Y01585*
X04179Y01584*
X04186Y01585*
X04191Y01589*
X04194Y01594*
X04196Y01601*
X04194Y01607*
X04191Y01612*
X04186Y01616*
X04179Y01617*
X04173Y01616*
X04169Y01613*
X04166Y01617*
X04166Y01617*
X04167Y01623*
X04166Y01629*
X04162Y01635*
X04157Y01638*
X04152Y01639*
X0415Y01643*
X04149Y01644*
X04149Y01644*
X04151Y01651*
X04149Y01657*
X04146Y01662*
X04141Y01666*
X04134Y01667*
G37*
G36*
X02719Y01607D02*
X02713Y01606D01*
X02708Y01602*
X02704Y01597*
X02703Y01591*
X02704Y01584*
X02708Y01579*
X02713Y01575*
X02719Y01574*
X02726Y01575*
X02731Y01579*
X02734Y01584*
X02736Y01591*
X02734Y01597*
X02731Y01602*
X02726Y01606*
X02719Y01607*
G37*
G36*
X03894Y01582D02*
X03888Y01581D01*
X03883Y01577*
X03879Y01572*
X03878Y01566*
X03879Y01559*
X03883Y01554*
X03888Y0155*
X03894Y01549*
X03901Y0155*
X03906Y01554*
X03909Y01559*
X03911Y01566*
X03909Y01572*
X03906Y01577*
X03901Y01581*
X03894Y01582*
G37*
G36*
X03969Y01568D02*
X03963Y01567D01*
X03958Y01563*
X03954Y01558*
X03953Y01552*
X03954Y01545*
X03958Y0154*
X03963Y01536*
X03969Y01535*
X03976Y01536*
X03978Y01538*
X03983Y01539*
X03985Y01537*
X03988Y01535*
X03994Y01534*
X04001Y01535*
X04006Y01539*
X04009Y01544*
X04011Y01551*
X04009Y01557*
X04006Y01562*
X04001Y01566*
X03994Y01567*
X03988Y01566*
X03983Y01562*
X03982*
X03981Y01563*
X03976Y01567*
X03969Y01568*
G37*
G36*
X04034Y01562D02*
X04028Y01561D01*
X04023Y01557*
X04019Y01552*
X04018Y01546*
X04019Y01539*
X04023Y01534*
X04028Y0153*
X04034Y01529*
X04041Y0153*
X04046Y01534*
X04049Y01539*
X04051Y01546*
X04049Y01552*
X04046Y01557*
X04041Y01561*
X04034Y01562*
G37*
G36*
X03924Y01552D02*
X03918Y01551D01*
X03913Y01547*
X03909Y01542*
X03908Y01536*
X03909Y01529*
X03913Y01524*
X03918Y0152*
X03924Y01519*
X03931Y0152*
X03936Y01524*
X03939Y01529*
X03941Y01536*
X03939Y01542*
X03936Y01547*
X03931Y01551*
X03924Y01552*
G37*
G36*
X02894Y01577D02*
X02888Y01576D01*
X02883Y01572*
X02879Y01567*
X02878Y01561*
X02879Y01554*
X02883Y01549*
X02888Y01545*
X02894Y01544*
X02901Y01545*
X02901Y01546*
X02904Y01542*
X02904Y01542*
X02903Y01536*
X02904Y01529*
X02908Y01524*
X02913Y0152*
X02919Y01519*
X02926Y0152*
X02931Y01524*
X02934Y01529*
X02936Y01536*
X02934Y01542*
X02931Y01547*
X02926Y01551*
X02919Y01552*
X02913Y01551*
X02913Y0155*
X02909Y01554*
X02909Y01554*
X02911Y01561*
X02909Y01567*
X02906Y01572*
X02901Y01576*
X02894Y01577*
G37*
G36*
X01719Y01552D02*
X01713Y01551D01*
X01708Y01547*
X01704Y01542*
X01703Y01536*
X01704Y01529*
X01708Y01524*
X01713Y0152*
X01719Y01519*
X01726Y0152*
X01731Y01524*
X01734Y01529*
X01736Y01536*
X01734Y01542*
X01731Y01547*
X01726Y01551*
X01719Y01552*
G37*
G36*
X01897Y01532D02*
X01891Y01531D01*
X01885Y01528*
X01882Y01522*
X0188Y01516*
X01882Y0151*
X01885Y01504*
X01891Y01501*
X01897Y015*
X01903Y01501*
X01908Y01504*
X01912Y0151*
X01913Y01516*
X01912Y01522*
X01908Y01528*
X01903Y01531*
X01897Y01532*
G37*
G36*
X04064Y01527D02*
X04058Y01526D01*
X04053Y01522*
X04049Y01517*
X04048Y01511*
X04049Y01504*
X04053Y01499*
X04058Y01495*
X04064Y01494*
X04071Y01495*
X04076Y01499*
X04079Y01504*
X04081Y01511*
X04079Y01517*
X04076Y01522*
X04071Y01526*
X04064Y01527*
G37*
G36*
X03864D02*
X03858Y01526D01*
X03853Y01522*
X03849Y01517*
X03848Y01511*
X03849Y01504*
X03853Y01499*
X03858Y01495*
X03864Y01494*
X03871Y01495*
X03876Y01499*
X03879Y01504*
X03881Y01511*
X03879Y01517*
X03876Y01522*
X03871Y01526*
X03864Y01527*
G37*
G36*
X02274Y01522D02*
X02268Y01521D01*
X02263Y01517*
X02259Y01512*
X02258Y01506*
X02259Y01499*
X02263Y01494*
X02268Y0149*
X02274Y01489*
X02281Y0149*
X02286Y01494*
X02289Y01499*
X02291Y01506*
X02289Y01512*
X02286Y01517*
X02281Y01521*
X02274Y01522*
G37*
G36*
X03834Y01497D02*
X03828Y01496D01*
X03823Y01492*
X03819Y01487*
X03818Y01481*
X03819Y01474*
X03823Y01469*
X03828Y01465*
X03834Y01464*
X03841Y01465*
X03846Y01469*
X03849Y01474*
X03851Y01481*
X03849Y01487*
X03846Y01492*
X03841Y01496*
X03834Y01497*
G37*
G36*
X02694D02*
X02688Y01496D01*
X02683Y01492*
X02679Y01487*
X02678Y01481*
X02679Y01474*
X02683Y01469*
X02688Y01465*
X02694Y01464*
X02701Y01465*
X02706Y01469*
X02709Y01474*
X02711Y01481*
X02709Y01487*
X02706Y01492*
X02701Y01496*
X02694Y01497*
G37*
G36*
X03549Y01457D02*
X03543Y01456D01*
X03538Y01452*
X03534Y01447*
X03533Y01441*
X03534Y01434*
X03538Y01429*
X03543Y01425*
X03549Y01424*
X03556Y01425*
X03561Y01429*
X03564Y01434*
X03566Y01441*
X03564Y01447*
X03561Y01452*
X03556Y01456*
X03549Y01457*
G37*
G36*
X02446Y01453D02*
X0244Y01452D01*
X02435Y01448*
X02431Y01443*
X0243Y01437*
X02431Y0143*
X02435Y01425*
X0244Y01421*
X02446Y0142*
X02453Y01421*
X02458Y01425*
X02461Y0143*
X02463Y01437*
X02461Y01443*
X02458Y01448*
X02453Y01452*
X02446Y01453*
G37*
G36*
X01008Y01446D02*
X01002Y01445D01*
X00997Y01441*
X00993Y01436*
X00992Y0143*
X00993Y01423*
X00997Y01418*
X01002Y01414*
X01008Y01413*
X01015Y01414*
X0102Y01418*
X01023Y01423*
X01025Y0143*
X01023Y01436*
X0102Y01441*
X01015Y01445*
X01008Y01446*
G37*
G36*
X02083Y01427D02*
X02077Y01426D01*
X02072Y01423*
X02068Y01417*
X02067Y01411*
X02068Y01405*
X02068Y01405*
X02066Y01402*
X02065Y01401*
X02059Y01402*
X02053Y01401*
X02048Y01397*
X02044Y01392*
X02043Y01386*
X02044Y01379*
X02048Y01374*
X02053Y0137*
X02059Y01369*
X02066Y0137*
X02071Y01374*
X02074Y01379*
X02076Y01386*
X02074Y01392*
X02074Y01392*
X02076Y01395*
X02078Y01396*
X02083Y01395*
X0209Y01396*
X02095Y014*
X02098Y01405*
X021Y01411*
X02098Y01417*
X02095Y01423*
X0209Y01426*
X02083Y01427*
G37*
G36*
X03407Y01427D02*
X03401Y01426D01*
X03395Y01422*
X03392Y01417*
X0339Y01411*
X03392Y01405*
X03395Y014*
X03391Y01397*
X03386Y01401*
X03379Y01402*
X03373Y01401*
X03368Y01397*
X03364Y01392*
X03363Y01386*
X03364Y01379*
X03368Y01374*
X03373Y0137*
X03379Y01369*
X03385Y0137*
X03388Y01368*
X03389Y01367*
X03388Y01363*
X03389Y01357*
X03392Y01353*
X03392Y01352*
X03389Y01349*
X03388Y01349*
X03386Y01351*
X03379Y01352*
X03373Y01351*
X03368Y01347*
X03364Y01342*
X03363Y01336*
X03364Y01329*
X03368Y01324*
X03373Y0132*
X03379Y01319*
X03386Y0132*
X03391Y01324*
X03394Y01329*
X03396Y01336*
X03394Y01342*
X03392Y01345*
X03392Y01346*
X03395Y0135*
X03396Y01349*
X03398Y01348*
X03404Y01347*
X03411Y01348*
X03416Y01351*
X03419Y01357*
X03421Y01363*
X03419Y01369*
X03416Y01374*
X03411Y01378*
X03404Y01379*
X03399Y01378*
X03396Y0138*
X03395Y01382*
X03396Y01386*
X03394Y01392*
X03391Y01396*
X03395Y01399*
X03401Y01396*
X03407Y01395*
X03413Y01396*
X03418Y01399*
X03422Y01405*
X03423Y01411*
X03422Y01417*
X03418Y01422*
X03413Y01426*
X03407Y01427*
G37*
G36*
X00199Y01495D02*
X00187Y01494D01*
X00175Y0149*
X00164Y01484*
X00154Y01476*
X00146Y01466*
X0014Y01455*
X00136Y01443*
X00135Y01431*
X00136Y01418*
X0014Y01406*
X00146Y01395*
X00154Y01385*
X00164Y01377*
X00175Y01371*
X00187Y01367*
X00199Y01366*
X00212Y01367*
X00224Y01371*
X00235Y01377*
X00245Y01385*
X00253Y01395*
X00259Y01406*
X00262Y01418*
X00264Y01431*
X00262Y01443*
X00259Y01455*
X00253Y01466*
X00245Y01476*
X00235Y01484*
X00224Y0149*
X00212Y01494*
X00199Y01495*
G37*
G36*
X02028Y01377D02*
X02022Y01376D01*
X02017Y01373*
X02013Y01367*
X02012Y01361*
X02013Y01355*
X02013Y01355*
X02011Y01352*
X0201Y01351*
X02004Y01352*
X01998Y01351*
X01993Y01347*
X01989Y01342*
X01988Y01336*
X01989Y01329*
X01993Y01324*
X01998Y0132*
X02004Y01319*
X02011Y0132*
X02016Y01324*
X02019Y01329*
X02021Y01336*
X02019Y01342*
X02019Y01342*
X02021Y01345*
X02023Y01346*
X02028Y01345*
X02035Y01346*
X0204Y0135*
X02043Y01355*
X02045Y01361*
X02043Y01367*
X0204Y01373*
X02035Y01376*
X02028Y01377*
G37*
G36*
X02502Y01332D02*
X02496Y01331D01*
X02491Y01327*
X02487Y01322*
X02486Y01316*
X02487Y01309*
X02491Y01304*
X02496Y013*
X02502Y01299*
X02509Y013*
X02514Y01304*
X02517Y01309*
X02519Y01316*
X02517Y01322*
X02514Y01327*
X02509Y01331*
X02502Y01332*
G37*
G36*
X01696Y01329D02*
X01689Y01327D01*
X01683Y01323*
X01679Y01317*
X01677Y01309*
X01679Y01302*
X01683Y01296*
X01689Y01292*
X01696Y0129*
X01704Y01292*
X0171Y01296*
X01714Y01302*
X01716Y01309*
X01714Y01317*
X0171Y01323*
X01704Y01327*
X01696Y01329*
G37*
G36*
X03571Y01328D02*
X03564Y01327D01*
X03558Y01323*
X03554Y01317*
X03552Y01309*
X03554Y01302*
X03558Y01296*
X03564Y01292*
X03571Y0129*
X03579Y01292*
X03585Y01296*
X03589Y01302*
X0359Y01309*
X03589Y01317*
X03585Y01323*
X03579Y01327*
X03571Y01328*
G37*
G36*
X01798Y0132D02*
X01791Y01319D01*
X01786Y01315*
X01783Y0131*
X01781Y01304*
X01783Y01297*
X01786Y01292*
X01791Y01289*
X01798Y01287*
X01804Y01289*
X01809Y01292*
X01813Y01297*
X01814Y01304*
X01813Y0131*
X01809Y01315*
X01804Y01319*
X01798Y0132*
G37*
G36*
X02206Y01314D02*
X022Y01313D01*
X02195Y01309*
X02191Y01304*
X0219Y01298*
X02191Y01291*
X02195Y01286*
X022Y01282*
X02206Y01281*
X02213Y01282*
X02218Y01286*
X02221Y01291*
X02223Y01298*
X02221Y01304*
X02218Y01309*
X02213Y01313*
X02206Y01314*
G37*
G36*
X01567Y01301D02*
X01561Y013D01*
X01556Y01296*
X01552Y01291*
X01551Y01285*
X01552Y01279*
X01556Y01273*
X01561Y0127*
X01567Y01269*
X01574Y0127*
X01579Y01273*
X01582Y01279*
X01584Y01285*
X01582Y01291*
X01579Y01296*
X01574Y013*
X01567Y01301*
G37*
G36*
X00996Y01203D02*
X00989Y01202D01*
X00984Y01198*
X0098Y01193*
X00979Y01187*
X0098Y0118*
X00984Y01175*
X00989Y01171*
X00996Y0117*
X01002Y01171*
X01007Y01175*
X01011Y0118*
X01012Y01187*
X01011Y01193*
X01007Y01198*
X01002Y01202*
X00996Y01203*
G37*
G36*
X02826Y00992D02*
X0282Y00991D01*
X02815Y00987*
X0281*
X02805Y00991*
X02799Y00992*
X02792Y00991*
X02787Y00987*
X02786Y00986*
X0278*
X02779Y00987*
X02773Y00991*
X02767Y00992*
X02761Y00991*
X02756Y00987*
X02751*
X02746Y00991*
X0274Y00992*
X02733Y00991*
X02728Y00987*
X02727Y00986*
X02721*
X0272Y00987*
X02714Y00991*
X02708Y00992*
X02702Y00991*
X02697Y00987*
X02692*
X02687Y00991*
X02681Y00992*
X02674Y00991*
X02669Y00987*
X02668Y00986*
X02662*
X02661Y00987*
X02655Y00991*
X02649Y00992*
X02643Y00991*
X02638Y00987*
X02633*
X02628Y00991*
X02622Y00992*
X02615Y00991*
X0261Y00987*
X02606Y00982*
X02605Y00976*
X02606Y0097*
X0261Y00964*
X02615Y00961*
X02622Y0096*
X02628Y00961*
X02633Y00964*
X02638*
X02643Y00961*
X02649Y0096*
X02655Y00961*
X02661Y00964*
X02662Y00966*
X02668*
X02669Y00964*
X02674Y00961*
X02681Y0096*
X02687Y00961*
X02692Y00964*
X02697*
X02702Y00961*
X02708Y0096*
X02714Y00961*
X0272Y00964*
X02721Y00966*
X02727*
X02728Y00964*
X02733Y00961*
X0274Y0096*
X02746Y00961*
X02751Y00964*
X02756*
X02761Y00961*
X02767Y0096*
X02773Y00961*
X02779Y00964*
X0278Y00966*
X02786*
X02787Y00964*
X02792Y00961*
X02799Y0096*
X02805Y00961*
X0281Y00964*
X02815*
X0282Y00961*
X02826Y0096*
X02833Y00961*
X02838Y00964*
X02841Y0097*
X02843Y00976*
X02841Y00982*
X02838Y00987*
X02833Y00991*
X02826Y00992*
G37*
G36*
X04366Y01045D02*
X04289D01*
Y00968*
X04366*
Y01045*
G37*
G36*
X05327Y01046D02*
X05317Y01045D01*
X05308Y01041*
X053Y01034*
X05294Y01026*
X0529Y01017*
X05288Y01007*
X0529Y00997*
X05294Y00988*
X053Y0098*
X05308Y00973*
X05317Y00969*
X05327Y00968*
X05337Y00969*
X05347Y00973*
X05355Y0098*
X05361Y00988*
X05365Y00997*
X05366Y01007*
X05365Y01017*
X05361Y01026*
X05355Y01034*
X05347Y01041*
X05337Y01045*
X05327Y01046*
G37*
G36*
X05127D02*
X05117Y01045D01*
X05108Y01041*
X051Y01034*
X05094Y01026*
X0509Y01017*
X05088Y01007*
X0509Y00997*
X05094Y00988*
X051Y0098*
X05108Y00973*
X05117Y00969*
X05127Y00968*
X05137Y00969*
X05147Y00973*
X05155Y0098*
X05161Y00988*
X05165Y00997*
X05166Y01007*
X05165Y01017*
X05161Y01026*
X05155Y01034*
X05147Y01041*
X05137Y01045*
X05127Y01046*
G37*
G36*
X04927D02*
X04917Y01045D01*
X04908Y01041*
X049Y01034*
X04894Y01026*
X0489Y01017*
X04888Y01007*
X0489Y00997*
X04894Y00988*
X049Y0098*
X04908Y00973*
X04917Y00969*
X04927Y00968*
X04937Y00969*
X04947Y00973*
X04955Y0098*
X04961Y00988*
X04965Y00997*
X04966Y01007*
X04965Y01017*
X04961Y01026*
X04955Y01034*
X04947Y01041*
X04937Y01045*
X04927Y01046*
G37*
G36*
X0299Y00977D02*
X02983Y00976D01*
X02976Y00972*
X02972Y00965*
X02971Y00958*
X02972Y00951*
X02976Y00945*
X02983Y0094*
X0299Y00939*
X02997Y0094*
X03004Y00945*
X03008Y00951*
X03009Y00958*
X03008Y00965*
X03004Y00972*
X02997Y00976*
X0299Y00977*
G37*
G36*
X02203D02*
X02195Y00976D01*
X02189Y00972*
X02185Y00965*
X02183Y00958*
X02185Y00951*
X02189Y00945*
X02195Y0094*
X02203Y00939*
X0221Y0094*
X02216Y00945*
X0222Y00951*
X02222Y00958*
X0222Y00965*
X02216Y00972*
X0221Y00976*
X02203Y00977*
G37*
G36*
X02478Y00953D02*
X02472Y00952D01*
X02467Y00948*
X02463Y00943*
X02462Y00937*
X02463Y0093*
X02467Y00925*
X02472Y00921*
X02478Y0092*
X02485Y00921*
X0249Y00925*
X02493Y0093*
X02495Y00937*
X02493Y00943*
X0249Y00948*
X02485Y00952*
X02478Y00953*
G37*
G36*
X01004Y00922D02*
X00998Y00921D01*
X00993Y00917*
X00989Y00912*
X00988Y00906*
X00989Y00899*
X00993Y00894*
X00998Y0089*
X01004Y00889*
X01011Y0089*
X01016Y00894*
X01019Y00899*
X01021Y00906*
X01019Y00912*
X01016Y00917*
X01011Y00921*
X01004Y00922*
G37*
G36*
X03617Y00983D02*
X03604Y00982D01*
X03592Y00978*
X0358Y00972*
X0357Y00963*
X03561Y00953*
X03555Y00942*
X03551Y00929*
X0355Y00916*
X03551Y00903*
X03555Y0089*
X03561Y00878*
X0357Y00868*
X0358Y0086*
X03592Y00854*
X03604Y0085*
X03617Y00848*
X03631Y0085*
X03643Y00854*
X03655Y0086*
X03665Y00868*
X03673Y00878*
X0368Y0089*
X03684Y00903*
X03685Y00916*
X03684Y00929*
X0368Y00942*
X03673Y00953*
X03665Y00963*
X03655Y00972*
X03643Y00978*
X03631Y00982*
X03617Y00983*
G37*
G36*
X01652D02*
X01639Y00982D01*
X01627Y00978*
X01615Y00972*
X01605Y00963*
X01596Y00953*
X0159Y00942*
X01586Y00929*
X01585Y00916*
X01586Y00903*
X0159Y0089*
X01596Y00878*
X01605Y00868*
X01615Y0086*
X01627Y00854*
X01639Y0085*
X01652Y00848*
X01666Y0085*
X01678Y00854*
X0169Y0086*
X017Y00868*
X01708Y00878*
X01715Y0089*
X01719Y00903*
X0172Y00916*
X01719Y00929*
X01715Y00942*
X01708Y00953*
X017Y00963*
X0169Y00972*
X01678Y00978*
X01666Y00982*
X01652Y00983*
G37*
G36*
X05578Y00936D02*
X05566Y00934D01*
X05555Y0093*
X05545Y00923*
X05538Y00913*
X05533Y00902*
X05532Y0089*
X05533Y00878*
X05538Y00867*
X05545Y00858*
X05555Y0085*
X05566Y00846*
X05578Y00844*
X0559Y00846*
X05601Y0085*
X0561Y00858*
X05617Y00867*
X05622Y00878*
X05624Y0089*
X05622Y00902*
X05617Y00913*
X0561Y00923*
X05601Y0093*
X0559Y00934*
X05578Y00936*
G37*
G36*
X03979D02*
X03967Y00934D01*
X03956Y0093*
X03947Y00923*
X03939Y00913*
X03935Y00902*
X03933Y0089*
X03935Y00878*
X03939Y00867*
X03947Y00858*
X03956Y0085*
X03967Y00846*
X03979Y00844*
X03991Y00846*
X04002Y0085*
X04012Y00858*
X04019Y00867*
X04024Y00878*
X04025Y0089*
X04024Y00902*
X04019Y00913*
X04012Y00923*
X04002Y0093*
X03991Y00934*
X03979Y00936*
G37*
G36*
X00199Y0097D02*
X00187Y00969D01*
X00175Y00965*
X00164Y00959*
X00154Y00951*
X00146Y00941*
X0014Y0093*
X00136Y00918*
X00135Y00906*
X00136Y00893*
X0014Y00881*
X00146Y0087*
X00154Y0086*
X00164Y00852*
X00175Y00846*
X00187Y00842*
X00199Y00841*
X00212Y00842*
X00224Y00846*
X00235Y00852*
X00245Y0086*
X00253Y0087*
X00259Y00881*
X00262Y00893*
X00264Y00906*
X00262Y00918*
X00259Y0093*
X00253Y00941*
X00245Y00951*
X00235Y00959*
X00224Y00965*
X00212Y00969*
X00199Y0097*
G37*
G36*
X02759Y00811D02*
X02753Y0081D01*
X02748Y00806*
X02743*
X02738Y0081*
X02732Y00811*
X02726Y0081*
X0272Y00806*
X02717Y00801*
X02715Y00795*
X02717Y00789*
X0272Y00783*
X02726Y0078*
X02732Y00778*
X02738Y0078*
X02743Y00783*
X02748*
X02753Y0078*
X02759Y00778*
X02766Y0078*
X02771Y00783*
X02774Y00789*
X02776Y00795*
X02774Y00801*
X02771Y00806*
X02766Y0081*
X02759Y00811*
G37*
G36*
X02692D02*
X02686Y0081D01*
X02681Y00806*
X02676*
X02671Y0081*
X02665Y00811*
X02659Y0081*
X02653Y00806*
X0265Y00801*
X02649Y00795*
X0265Y00789*
X02653Y00783*
X02659Y0078*
X02665Y00778*
X02671Y0078*
X02676Y00783*
X02681*
X02686Y0078*
X02692Y00778*
X02699Y0078*
X02704Y00783*
X02707Y00789*
X02709Y00795*
X02707Y00801*
X02704Y00806*
X02699Y0081*
X02692Y00811*
G37*
G36*
X02625D02*
X02619Y0081D01*
X02614Y00806*
X02609*
X02604Y0081*
X02598Y00811*
X02592Y0081*
X02586Y00806*
X02583Y00801*
X02582Y00795*
X02583Y00789*
X02586Y00783*
X02592Y0078*
X02598Y00778*
X02604Y0078*
X02609Y00783*
X02614*
X02619Y0078*
X02625Y00778*
X02632Y0078*
X02637Y00783*
X02641Y00789*
X02642Y00795*
X02641Y00801*
X02637Y00806*
X02632Y0081*
X02625Y00811*
G37*
G36*
X02893D02*
X02887Y0081D01*
X02882Y00806*
X0288Y00805*
X02874*
X02873Y00806*
X02868Y0081*
X02862Y00811*
X02855Y0081*
X0285Y00806*
X02847Y00801*
X02847Y00801*
X02841*
X02841Y00801*
X02838Y00806*
X02833Y0081*
X02826Y00811*
X0282Y0081*
X02815Y00806*
X0281*
X02805Y0081*
X02799Y00811*
X02792Y0081*
X02787Y00806*
X02784Y00801*
X02782Y00795*
X02784Y00789*
X02787Y00783*
X02792Y0078*
X02799Y00778*
X02805Y0078*
X0281Y00783*
X02815*
X0282Y0078*
X02826Y00778*
X02833Y0078*
X02838Y00783*
X02841Y00789*
X02841Y00789*
X02847*
X02847Y00789*
X0285Y00783*
X02855Y0078*
X02862Y00778*
X02868Y0078*
X02873Y00783*
X02874Y00785*
X0288*
X02882Y00783*
X02887Y0078*
X02893Y00778*
X02899Y0078*
X02905Y00783*
X02908Y00789*
X0291Y00795*
X02908Y00801*
X02905Y00806*
X02899Y0081*
X02893Y00811*
G37*
G36*
X0099Y00703D02*
X00983Y00702D01*
X00978Y00698*
X00975Y00693*
X00973Y00687*
X00975Y0068*
X00978Y00675*
X00983Y00671*
X0099Y0067*
X00996Y00671*
X01001Y00675*
X01005Y0068*
X01006Y00687*
X01005Y00693*
X01001Y00698*
X00996Y00702*
X0099Y00703*
G37*
G36*
X02469Y00427D02*
X02463Y00426D01*
X02458Y00422*
X02454Y00417*
X02453Y0041*
X02454Y00404*
X02458Y00399*
X02463Y00395*
X02469Y00394*
X02476Y00395*
X02481Y00399*
X02484Y00404*
X02486Y0041*
X02484Y00417*
X02481Y00422*
X02476Y00426*
X02469Y00427*
G37*
G36*
X0298Y00425D02*
X02974Y00424D01*
X02968Y0042*
X02965Y00415*
X02964Y00409*
X02965Y00402*
X02968Y00397*
X02974Y00394*
X0298Y00392*
X02986Y00394*
X02991Y00397*
X02995Y00402*
X02996Y00409*
X02995Y00415*
X02991Y0042*
X02986Y00424*
X0298Y00425*
G37*
G36*
X03019Y00421D02*
X03013Y0042D01*
X03008Y00417*
X03004Y00411*
X03003Y00405*
X03004Y00399*
X03008Y00393*
X03013Y0039*
X03019Y00389*
X03025Y0039*
X03031Y00393*
X03034Y00399*
X03036Y00405*
X03034Y00411*
X03031Y00417*
X03025Y0042*
X03019Y00421*
G37*
G36*
X02821Y00424D02*
X02815Y00422D01*
X0281Y00419*
X02806Y00414*
X02805Y00407*
X02806Y00401*
X0281Y00396*
X02815Y00392*
X02821Y00391*
X02828Y00392*
X02833Y00396*
X02834Y00397*
X02835Y00398*
X0284Y00397*
X02842Y00393*
X02848Y0039*
X02854Y00389*
X0286Y0039*
X02865Y00393*
X02869Y00399*
X0287Y00405*
X02869Y00411*
X02865Y00417*
X0286Y0042*
X02854Y00421*
X02848Y0042*
X02842Y00417*
X02841Y00415*
X02841Y00415*
X02835Y00415*
X02833Y00419*
X02828Y00422*
X02821Y00424*
G37*
G36*
X02704Y00421D02*
X02698Y0042D01*
X02693Y00417*
X02689Y00411*
X02688Y00405*
X02689Y00399*
X02693Y00393*
X02698Y0039*
X02704Y00389*
X0271Y0039*
X02716Y00393*
X02719Y00399*
X02721Y00405*
X02719Y00411*
X02716Y00417*
X0271Y0042*
X02704Y00421*
G37*
G36*
X02665D02*
X02659Y0042D01*
X02653Y00417*
X0265Y00411*
X02649Y00405*
X0265Y00399*
X02653Y00393*
X02659Y0039*
X02665Y00389*
X02671Y0039*
X02676Y00393*
X0268Y00399*
X02681Y00405*
X0268Y00411*
X02676Y00417*
X02671Y0042*
X02665Y00421*
G37*
G36*
X02511D02*
X02505Y0042D01*
X025Y00417*
X02496Y00411*
X02495Y00405*
X02496Y00399*
X025Y00393*
X02505Y0039*
X02511Y00389*
X02518Y0039*
X02523Y00393*
X02526Y00399*
X02528Y00405*
X02526Y00411*
X02523Y00417*
X02518Y0042*
X02511Y00421*
G37*
G36*
X02389D02*
X02383Y0042D01*
X02378Y00417*
X02374Y00411*
X02373Y00405*
X02374Y00399*
X02378Y00393*
X02383Y0039*
X02389Y00389*
X02396Y0039*
X02401Y00393*
X02404Y00399*
X02406Y00405*
X02404Y00411*
X02401Y00417*
X02396Y0042*
X02389Y00421*
G37*
G36*
X0235D02*
X02344Y0042D01*
X02338Y00417*
X02335Y00411*
X02334Y00405*
X02335Y00399*
X02338Y00393*
X02344Y0039*
X0235Y00389*
X02356Y0039*
X02361Y00393*
X02365Y00399*
X02366Y00405*
X02365Y00411*
X02361Y00417*
X02356Y0042*
X0235Y00421*
G37*
G36*
X01872Y00303D02*
X01865Y00302D01*
X01862Y003*
X01858Y00302*
X01852Y00303*
X01846Y00302*
X01842Y003*
X01838Y00302*
X01832Y00303*
X01826Y00302*
X01821Y00298*
X01817Y00293*
X01816Y00287*
X01817Y00281*
X01821Y00275*
X01822Y00274*
Y00268*
X01821Y00267*
X01817Y00262*
X01816Y00255*
X01817Y00249*
X01821Y00244*
X01826Y0024*
X01832Y00239*
X01838Y0024*
X01842Y00243*
X01846Y0024*
X01852Y00239*
X01858Y0024*
X01862Y00243*
X01865Y0024*
X01872Y00239*
X01878Y0024*
X01883Y00244*
X01887Y00249*
X01888Y00255*
X01887Y00262*
X01883Y00267*
X01881Y00268*
Y00274*
X01883Y00275*
X01887Y00281*
X01888Y00287*
X01887Y00293*
X01883Y00298*
X01878Y00302*
X01872Y00303*
G37*
G36*
X00285Y00439D02*
X00271Y00437D01*
X00258Y00433*
X00246Y00427*
X00235Y00418*
X00226Y00407*
X00219Y00395*
X00215Y00381*
X00214Y00368*
X00215Y00354*
X00219Y0034*
X00226Y00328*
X00235Y00317*
X00246Y00309*
X00258Y00302*
X00271Y00298*
X00285Y00297*
X00299Y00298*
X00312Y00302*
X00324Y00309*
X00335Y00317*
X00344Y00328*
X0035Y0034*
X00355Y00354*
X00356Y00368*
X00355Y00381*
X0035Y00395*
X00344Y00407*
X00335Y00418*
X00324Y00427*
X00312Y00433*
X00299Y00437*
X00285Y00439*
G37*
G36*
X02112Y00303D02*
X02105Y00302D01*
X021Y00298*
X02097Y00293*
X02097Y00293*
X02091*
X02091Y00293*
X02088Y00298*
X02083Y00302*
X02076Y00303*
X0207Y00302*
X02065Y00298*
X02061Y00293*
X0206Y00287*
X02061Y00281*
X02065Y00275*
X02067Y00274*
Y00268*
X02065Y00267*
X02061Y00262*
X0206Y00255*
X02061Y00249*
X02065Y00244*
X0207Y0024*
X02076Y00239*
X02083Y0024*
X02088Y00244*
X02091Y00249*
X02091Y0025*
X02097*
X02097Y00249*
X021Y00244*
X02105Y0024*
X02112Y00239*
X02118Y0024*
X02123Y00244*
X02127Y00249*
X02128Y00255*
X02127Y00262*
X02123Y00267*
X02121Y00268*
Y00274*
X02123Y00275*
X02127Y00281*
X02128Y00287*
X02127Y00293*
X02123Y00298*
X02118Y00302*
X02112Y00303*
G37*
G36*
X0261Y00295D02*
X02603Y00294D01*
X02598Y00291*
X02597Y00289*
X02591*
X0259Y00291*
X02584Y00294*
X02578Y00295*
X02572Y00294*
X02567Y00291*
X02563Y00285*
X02562Y00279*
X02563Y00273*
X02567Y00267*
X02572Y00264*
X02578Y00263*
X02584Y00264*
X0259Y00267*
X02591Y00269*
X02597*
X02598Y00267*
X02603Y00264*
X0261Y00263*
X02616Y00264*
X02621Y00267*
X02625Y00273*
X02626Y00279*
X02625Y00285*
X02621Y00291*
X02616Y00294*
X0261Y00295*
G37*
G36*
X02444D02*
X02438Y00294D01*
X02433Y00291*
X02432Y00289*
X02426*
X02424Y00291*
X02419Y00294*
X02413Y00295*
X02407Y00294*
X02401Y00291*
X02398Y00285*
X02397Y00279*
X02398Y00273*
X02401Y00267*
X02407Y00264*
X02413Y00263*
X02419Y00264*
X02424Y00267*
X02426Y00269*
X02432*
X02433Y00267*
X02438Y00264*
X02444Y00263*
X02451Y00264*
X02456Y00267*
X02459Y00273*
X02461Y00279*
X02459Y00285*
X02456Y00291*
X02451Y00294*
X02444Y00295*
G37*
G36*
X02937D02*
X0293Y00294D01*
X02925Y00291*
X02924Y00289*
X02918*
X02917Y00291*
X02911Y00294*
X02905Y00295*
X02899Y00294*
X02893Y00291*
X0289Y00285*
X02889Y00279*
X0289Y00273*
X02893Y00267*
X02899Y00264*
X02905Y00263*
X02911Y00264*
X02917Y00267*
X02918Y00269*
X02924*
X02925Y00267*
X0293Y00264*
X02937Y00263*
X02943Y00264*
X02948Y00267*
X02952Y00273*
X02953Y00279*
X02952Y00285*
X02948Y00291*
X02943Y00294*
X02937Y00295*
G37*
G36*
X02748Y00298D02*
X02742Y00297D01*
X02737Y00293*
X02733Y00288*
X02732Y00282*
X02733Y00276*
X02737Y0027*
X02742Y00267*
X02748Y00266*
X02755Y00267*
X0276Y0027*
X02766Y0027*
X02767Y00267*
X02773Y00264*
X02779Y00263*
X02785Y00264*
X02791Y00267*
X02794Y00273*
X02795Y00279*
X02794Y00285*
X02791Y00291*
X02785Y00294*
X02779Y00295*
X02773Y00294*
X02767Y00291*
X02762Y00291*
X0276Y00293*
X02755Y00297*
X02748Y00298*
G37*
G36*
X02151Y00303D02*
X02145Y00302D01*
X0214Y00298*
X02136Y00293*
X02135Y00287*
X02136Y00281*
X0214Y00275*
X02141Y00274*
Y00268*
X0214Y00267*
X02136Y00262*
X02135Y00255*
X02136Y00249*
X0214Y00244*
X02145Y0024*
X02151Y00239*
X02157Y0024*
X02163Y00244*
X02166Y00249*
X02167Y00255*
X02166Y00262*
X02163Y00267*
X02161Y00268*
Y00274*
X02163Y00275*
X02166Y00281*
X02167Y00287*
X02166Y00293*
X02163Y00298*
X02157Y00302*
X02151Y00303*
G37*
%LNgrandmaster-3*%
%LPD*%
G54D143*
X00299Y01006D03*
Y00806D03*
X00099D03*
Y01006D03*
X00299Y02581D03*
Y02381D03*
X00099D03*
Y02581D03*
X00299Y02056D03*
Y01856D03*
X00099D03*
Y02056D03*
X00299Y01531D03*
Y01331D03*
X00099D03*
Y01531D03*
G54D150*
X00285Y04152D03*
Y00368D03*
G54D159*
X05127Y02307D03*
G54D161*
X05578Y01689D03*
X03979Y02489D03*
G54D162*
X069Y03589D03*
X06734D03*
X06569D03*
G54D163*
X05934Y03937D03*
G54D164*
X06119Y04056D03*
G54D171*
X02878Y00249D03*
X02957Y00251D03*
X02447Y00242D03*
X02606Y00931D03*
X02636Y00247D03*
X02799Y00251D03*
X02409Y01088D03*
X02311Y0109D03*
X02508Y00931D03*
X02409Y00932D03*
X02724Y01093D03*
X02784Y01094D03*
X02842Y01095D03*
X02546Y00244D03*
X03097Y00251D03*
X02606Y01091D03*
X03554Y01841D03*
X03719Y01996D03*
X01721Y0189D03*
X01671Y01792D03*
X01674Y01989D03*
X02508Y0109D03*
X03413Y01573D03*
X0167Y01595D03*
X02409Y02579D03*
X02586Y02569D03*
X01718Y01792D03*
X02881Y02566D03*
X03732Y01418D03*
X02253Y02279D03*
X02311Y00934D03*
X03554Y01991D03*
X01675Y01891D03*
X02783Y02429D03*
X03719Y01921D03*
X02665Y01092D03*
X02475Y02456D03*
X03414Y01805D03*
X02685Y02311D03*
X0359Y01662D03*
X02404Y02412D03*
X01716Y01399D03*
X01721Y01989D03*
X03549Y01413D03*
X02488Y02413D03*
X0167Y01694D03*
X02901Y01095D03*
X03594Y01514D03*
X03406Y01461D03*
X0341Y01713D03*
X02933Y00953D03*
X02871Y02297D03*
X02685Y02568D03*
X03554Y01941D03*
X02783Y02568D03*
X03718Y01713D03*
X01721Y01694D03*
X01671Y01399D03*
X02581Y02308D03*
X01718Y01497D03*
X01714Y01595D03*
X01671Y01497D03*
X02321Y02586D03*
X02034Y00246D03*
X01916Y00244D03*
X02309Y00246D03*
X0333Y03301D03*
X0412Y03594D03*
X03183Y03135D03*
X03277Y02963D03*
X02419Y02788D03*
X02413Y03295D03*
X02321Y03361D03*
X02631Y02876D03*
X02473Y0298D03*
X00937Y02317D03*
X01726Y04329D03*
X01788D03*
X04477Y03135D03*
X04064Y02722D03*
X06628Y01372D03*
X06974Y01939D03*
X03968Y01671D03*
X04131Y01686D03*
X03996Y01711D03*
X0396Y02724D03*
X06253Y02909D03*
X06647Y03129D03*
X04339Y02725D03*
X0383Y03762D03*
X03395Y04222D03*
X04272Y03135D03*
X02139Y03738D03*
X04208Y03135D03*
X06626Y03032D03*
X04152Y03135D03*
X02724Y03521D03*
X01248Y02D03*
X04068Y03135D03*
X02674Y03501D03*
X04234Y02725D03*
X06456Y03009D03*
X01691Y04079D03*
X03642Y00636D03*
X04039Y03784D03*
X06476Y03231D03*
X04333Y03135D03*
X01261Y02482D03*
X04114Y03135D03*
X06648Y03341D03*
X02888Y04221D03*
X0337Y02888D03*
X02258Y03741D03*
X01749Y0411D03*
X0229Y04217D03*
X0388Y03109D03*
X03744Y03342D03*
X03717Y03072D03*
X05733Y03556D03*
X05676Y03546D03*
X03603Y00682D03*
X06548Y01531D03*
X06602Y01612D03*
Y01672D03*
Y01722D03*
X06601Y01777D03*
X06685Y01828D03*
X06699Y01881D03*
X06949Y02095D03*
X06607Y02176D03*
X06395Y02111D03*
X06048Y02171D03*
X06004Y02434D03*
X06274Y02391D03*
X06398Y02453D03*
X06397Y02501D03*
X06396Y02556D03*
X06397Y0261D03*
X06398Y02657D03*
X06372Y02909D03*
X0491Y04203D03*
X04387Y04206D03*
X03777Y04023D03*
X04085Y03892D03*
X04194Y03884D03*
X04431Y03135D03*
X0286Y03787D03*
X02724Y03729D03*
X03531Y0366D03*
X03269Y03788D03*
X01242Y01472D03*
X01256Y00942D03*
X00654Y0079D03*
X00655Y01028D03*
X00654Y01314D03*
X00653Y01551D03*
X00654Y01839D03*
Y02073D03*
Y02365D03*
X00653Y02593D03*
G54D172*
X02531Y03853D03*
Y0283D03*
X00149D03*
Y03853D03*
M02*